FILE_TYPE = MACRO_DRAWING;
SET COLOR_WIRE YELLOW;
SET COLOR_PROP MONO;
SET COLOR_DOT WHITE;
SET COLOR_ARC YELLOW;
SET COLOR_BODY GREEN;
SET COLOR_NOTE MONO;
SET PROP_DISPLAY VALUE;
SET PAGE_NUMBER P153;
FORCEADD OFFPAGE..1
(-7150 3725);
FORCEPROP 2 LAST $XR0 154 
J 0
(-7402 3725);
DISPLAY 0.638298 (-7402 3725);
PAINT MONO (-7402 3725);
FORCEPROP 2 LAST PATH I101
J 0
(-7400 3775);
DISPLAY 1.021277 (-7400 3775);
PAINT ORANGE (-7400 3775);
DISPLAY INVISIBLE (-7400 3775);
FORCEPROP 1 LAST COMMENT_BODY TRUE
J 0
(-7025 3625);
DISPLAY 0.978723 (-7025 3625);
PAINT PEACH (-7025 3625);
DISPLAY INVISIBLE (-7025 3625);
FORCEPROP 2 LAST CDS_LIB mstr_standard
J 0
(-7150 3725);
DISPLAY 1.531915 (-7150 3725);
PAINT ORANGE (-7150 3725);
DISPLAY INVISIBLE (-7150 3725);
FORCEPROP 1 LAST OFFPAGE TRUE
J 0
(-6825 3600);
PAINT GREEN (-6825 3600);
DISPLAY INVISIBLE (-6825 3600);
FORCEADD OFFPAGE..1
(-7150 3825);
FORCEPROP 2 LAST $XR0 154 
J 0
(-7402 3825);
DISPLAY 0.638298 (-7402 3825);
PAINT MONO (-7402 3825);
FORCEPROP 2 LAST $XR1 153 
J 0
(-7522 3825);
DISPLAY 0.638298 (-7522 3825);
PAINT MONO (-7522 3825);
FORCEPROP 2 LAST PATH I102
J 0
(-7400 3875);
DISPLAY 1.021277 (-7400 3875);
PAINT ORANGE (-7400 3875);
DISPLAY INVISIBLE (-7400 3875);
FORCEPROP 1 LAST COMMENT_BODY TRUE
J 0
(-7025 3725);
DISPLAY 0.978723 (-7025 3725);
PAINT PEACH (-7025 3725);
DISPLAY INVISIBLE (-7025 3725);
FORCEPROP 2 LAST CDS_LIB mstr_standard
J 0
(-7150 3825);
DISPLAY 1.531915 (-7150 3825);
PAINT ORANGE (-7150 3825);
DISPLAY INVISIBLE (-7150 3825);
FORCEPROP 1 LAST OFFPAGE TRUE
J 0
(-6825 3700);
PAINT GREEN (-6825 3700);
DISPLAY INVISIBLE (-6825 3700);
FORCEADD OFFPAGE..5
(-7150 3975);
FORCEPROP 2 LAST $XR0 153 
J 0
(-7405 3975);
DISPLAY 0.638298 (-7405 3975);
PAINT MONO (-7405 3975);
FORCEPROP 2 LAST $XR1 154 
J 0
(-7525 3975);
DISPLAY 0.638298 (-7525 3975);
PAINT MONO (-7525 3975);
FORCEPROP 2 LAST PATH I103
J 0
(-7425 4025);
DISPLAY 1.021277 (-7425 4025);
PAINT ORANGE (-7425 4025);
DISPLAY INVISIBLE (-7425 4025);
FORCEPROP 1 LAST COMMENT_BODY TRUE
J 0
(-7050 3900);
DISPLAY 1.170213 (-7050 3900);
PAINT GREEN (-7050 3900);
DISPLAY INVISIBLE (-7050 3900);
FORCEPROP 2 LAST CDS_LIB mstr_standard
J 1
(-7150 3975);
PAINT ORANGE (-7150 3975);
DISPLAY INVISIBLE (-7150 3975);
FORCEPROP 1 LAST OFFPAGE TRUE
J 0
(-6825 3850);
PAINT GREEN (-6825 3850);
DISPLAY INVISIBLE (-6825 3850);
FORCEADD OFFPAGE..1
(-7150 4025);
FORCEPROP 2 LAST $XR0 153 
J 0
(-7402 4025);
DISPLAY 0.638298 (-7402 4025);
PAINT MONO (-7402 4025);
FORCEPROP 2 LAST CDS_LIB mstr_standard
J 0
(-7150 4025);
PAINT ORANGE (-7150 4025);
DISPLAY INVISIBLE (-7150 4025);
FORCEPROP 1 LAST COMMENT_BODY TRUE
J 0
(-7025 3925);
DISPLAY 0.872340 (-7025 3925);
PAINT GREEN (-7025 3925);
DISPLAY INVISIBLE (-7025 3925);
FORCEPROP 1 LAST OFFPAGE TRUE
J 0
(-6825 3900);
DISPLAY 0.872340 (-6825 3900);
PAINT GREEN (-6825 3900);
DISPLAY INVISIBLE (-6825 3900);
FORCEPROP 2 LAST PATH I105
J 0
(-7100 4100);
DISPLAY 1.021277 (-7100 4100);
PAINT ORANGE (-7100 4100);
DISPLAY INVISIBLE (-7100 4100);
FORCEADD OFFPAGE..1
(-7150 4075);
FORCEPROP 2 LAST $XR0 153 
J 0
(-7402 4075);
DISPLAY 0.638298 (-7402 4075);
PAINT MONO (-7402 4075);
FORCEPROP 1 LAST COMMENT_BODY TRUE
J 0
(-7025 3975);
DISPLAY 0.872340 (-7025 3975);
PAINT GREEN (-7025 3975);
DISPLAY INVISIBLE (-7025 3975);
FORCEPROP 1 LAST OFFPAGE TRUE
J 0
(-6825 3950);
DISPLAY 0.872340 (-6825 3950);
PAINT GREEN (-6825 3950);
DISPLAY INVISIBLE (-6825 3950);
FORCEPROP 2 LAST CDS_LIB mstr_standard
J 0
(-7150 4075);
PAINT ORANGE (-7150 4075);
DISPLAY INVISIBLE (-7150 4075);
FORCEPROP 2 LAST PATH I107
J 0
(-7100 4150);
DISPLAY 1.021277 (-7100 4150);
PAINT ORANGE (-7100 4150);
DISPLAY INVISIBLE (-7100 4150);
FORCEADD RES..1
(-6500 3600);
FORCEPROP 1 LAST WATTAGE 1/16W
J 2
(-6700 3525);
DISPLAY 0.617021 (-6700 3525);
PAINT SKYBLUE (-6700 3525);
FORCEPROP 1 LAST VALUE 33.2
J 2
(-6575 3525);
DISPLAY 0.617021 (-6575 3525);
PAINT SKYBLUE (-6575 3525);
FORCEPROP 1 LAST PART_NUMBER G21796-074
J 0
(-6700 3450);
DISPLAY 0.617021 (-6700 3450);
PAINT BLUE (-6700 3450);
FORCEPROP 1 LAST TOLERANCE 1%
J 0
(-6475 3525);
DISPLAY 0.617021 (-6475 3525);
PAINT SKYBLUE (-6475 3525);
FORCEPROP 1 LAST MATERIAL CHIP
J 0
(-6350 3525);
DISPLAY 0.617021 (-6350 3525);
PAINT SKYBLUE (-6350 3525);
FORCEPROP 1 LAST LOCATION R7F37
J 0
(-6550 3650);
DISPLAY 0.617021 (-6550 3650);
PAINT AQUA (-6550 3650);
FORCEPROP 1 LAST PACK_TYPE 0402
J 0
(-6175 3525);
DISPLAY 0.617021 (-6175 3525);
PAINT SKYBLUE (-6175 3525);
FORCEPROP 1 LASTPIN (-6600 3600) $PN 1
J 0
(-6588 3612);
DISPLAY 0.787234 (-6588 3612);
PAINT ORANGE (-6588 3612);
DISPLAY INVISIBLE (-6588 3612);
FORCEPROP 2 LAST ROOM SB_SPI
J 0
(-6550 3700);
DISPLAY 1.021277 (-6550 3700);
PAINT ORANGE (-6550 3700);
DISPLAY INVISIBLE (-6550 3700);
FORCEPROP 2 LAST BOM_COST MIO_BIOS_MEM
J 0
(-6550 3750);
DISPLAY 1.021277 (-6550 3750);
PAINT ORANGE (-6550 3750);
DISPLAY INVISIBLE (-6550 3750);
FORCEPROP 1 LAST PATH I108
J 0
(-6550 3750);
DISPLAY 0.978723 (-6550 3750);
PAINT WHITE (-6550 3750);
DISPLAY INVISIBLE (-6550 3750);
FORCEPROP 1 LASTPIN (-6400 3600) $PN 2
J 0
(-6438 3612);
DISPLAY 0.787234 (-6438 3612);
PAINT ORANGE (-6438 3612);
DISPLAY INVISIBLE (-6438 3612);
FORCEPROP 2 LAST CDS_LIB mstr_discrete
J 0
(-6500 3600);
PAINT ORANGE (-6500 3600);
DISPLAY INVISIBLE (-6500 3600);
FORCEPROP 2 LAST $SEC 1
J 0
(-6550 3800);
PAINT MONO (-6550 3800);
DISPLAY INVISIBLE (-6550 3800);
FORCEPROP 2 LAST CDS_SEC 1
J 0
(-6550 3800);
PAINT MONO (-6550 3800);
DISPLAY INVISIBLE (-6550 3800);
FORCEADD RES..1
(-6475 3325);
FORCEPROP 1 LAST WATTAGE 1/16W
J 2
(-6675 3250);
DISPLAY 0.617021 (-6675 3250);
PAINT SKYBLUE (-6675 3250);
FORCEPROP 1 LAST VALUE 33.2
J 2
(-6550 3250);
DISPLAY 0.617021 (-6550 3250);
PAINT SKYBLUE (-6550 3250);
FORCEPROP 1 LAST PART_NUMBER G21796-074
J 0
(-6675 3175);
DISPLAY 0.617021 (-6675 3175);
PAINT BLUE (-6675 3175);
FORCEPROP 1 LAST LOCATION R7F3
J 0
(-6525 3375);
DISPLAY 0.617021 (-6525 3375);
PAINT AQUA (-6525 3375);
FORCEPROP 1 LAST TOLERANCE 1%
J 0
(-6450 3250);
DISPLAY 0.617021 (-6450 3250);
PAINT SKYBLUE (-6450 3250);
FORCEPROP 1 LAST MATERIAL CHIP
J 0
(-6325 3250);
DISPLAY 0.617021 (-6325 3250);
PAINT SKYBLUE (-6325 3250);
FORCEPROP 1 LAST PACK_TYPE 0402
J 0
(-6150 3250);
DISPLAY 0.617021 (-6150 3250);
PAINT SKYBLUE (-6150 3250);
FORCEPROP 2 LAST CDS_LIB mstr_discrete
J 0
(-6475 3325);
PAINT ORANGE (-6475 3325);
DISPLAY INVISIBLE (-6475 3325);
FORCEPROP 2 LAST $SEC 1
J 0
(-6525 3525);
PAINT MONO (-6525 3525);
DISPLAY INVISIBLE (-6525 3525);
FORCEPROP 1 LASTPIN (-6375 3325) $PN 2
J 0
(-6413 3337);
DISPLAY 0.787234 (-6413 3337);
PAINT ORANGE (-6413 3337);
DISPLAY INVISIBLE (-6413 3337);
FORCEPROP 2 LAST ROOM SB_SPI
J 0
(-6525 3425);
DISPLAY 1.021277 (-6525 3425);
PAINT ORANGE (-6525 3425);
DISPLAY INVISIBLE (-6525 3425);
FORCEPROP 2 LAST CDS_SEC 1
J 0
(-6525 3525);
PAINT MONO (-6525 3525);
DISPLAY INVISIBLE (-6525 3525);
FORCEPROP 2 LAST NO_XNET_CONNECTION 1
J 0
(-6525 3525);
PAINT MONO (-6525 3525);
DISPLAY INVISIBLE (-6525 3525);
FORCEPROP 1 LAST PATH I109
J 0
(-6525 3475);
DISPLAY 0.978723 (-6525 3475);
PAINT WHITE (-6525 3475);
DISPLAY INVISIBLE (-6525 3475);
FORCEPROP 1 LASTPIN (-6575 3325) $PN 1
J 0
(-6563 3337);
DISPLAY 0.787234 (-6563 3337);
PAINT ORANGE (-6563 3337);
DISPLAY INVISIBLE (-6563 3337);
FORCEPROP 2 LAST CDS_LOCATION R7F3
J 0
(-6525 3375);
DISPLAY 0.617021 (-6525 3375);
PAINT AQUA (-6525 3375);
DISPLAY INVISIBLE (-6525 3375);
FORCEPROP 2 LAST BOM_COST MIO_BIOS_MEM
J 0
(-6525 3475);
DISPLAY 1.021277 (-6525 3475);
PAINT ORANGE (-6525 3475);
DISPLAY INVISIBLE (-6525 3475);
FORCEADD OFFPAGE..1
(-7375 3600);
FORCEPROP 2 LAST $XR0 154 
J 0
(-7627 3600);
DISPLAY 0.638298 (-7627 3600);
PAINT MONO (-7627 3600);
FORCEPROP 2 LAST $XR1 153 
J 0
(-7747 3600);
DISPLAY 0.638298 (-7747 3600);
PAINT MONO (-7747 3600);
FORCEPROP 1 LAST COMMENT_BODY TRUE
J 0
(-7250 3500);
DISPLAY 0.872340 (-7250 3500);
PAINT GREEN (-7250 3500);
DISPLAY INVISIBLE (-7250 3500);
FORCEPROP 2 LAST PATH I110
J 0
(-7325 3675);
DISPLAY 1.021277 (-7325 3675);
PAINT ORANGE (-7325 3675);
DISPLAY INVISIBLE (-7325 3675);
FORCEPROP 2 LAST CDS_LIB mstr_standard
J 0
(-7375 3600);
PAINT ORANGE (-7375 3600);
DISPLAY INVISIBLE (-7375 3600);
FORCEPROP 1 LAST OFFPAGE TRUE
J 0
(-7050 3475);
DISPLAY 0.872340 (-7050 3475);
PAINT GREEN (-7050 3475);
DISPLAY INVISIBLE (-7050 3475);
FORCEADD OFFPAGE..1
(-7375 3325);
FORCEPROP 2 LAST $XR0 154 
J 0
(-7627 3325);
DISPLAY 0.638298 (-7627 3325);
PAINT MONO (-7627 3325);
FORCEPROP 2 LAST $XR1 153 
J 0
(-7747 3325);
DISPLAY 0.638298 (-7747 3325);
PAINT MONO (-7747 3325);
FORCEPROP 2 LAST PATH I111
J 0
(-7325 3400);
DISPLAY 1.021277 (-7325 3400);
PAINT ORANGE (-7325 3400);
DISPLAY INVISIBLE (-7325 3400);
FORCEPROP 1 LAST COMMENT_BODY TRUE
J 0
(-7250 3225);
DISPLAY 0.872340 (-7250 3225);
PAINT GREEN (-7250 3225);
DISPLAY INVISIBLE (-7250 3225);
FORCEPROP 2 LAST CDS_LIB mstr_standard
J 0
(-7375 3325);
PAINT ORANGE (-7375 3325);
DISPLAY INVISIBLE (-7375 3325);
FORCEPROP 1 LAST OFFPAGE TRUE
J 0
(-7050 3200);
DISPLAY 0.872340 (-7050 3200);
PAINT GREEN (-7050 3200);
DISPLAY INVISIBLE (-7050 3200);
FORCEADD CAP_A..1
(-4075 4500);
FORCEPROP 1 LAST PACK_TYPE 0402V
J 0
(-4025 4300);
DISPLAY 0.617021 (-4025 4300);
PAINT SKYBLUE (-4025 4300);
FORCEPROP 1 LAST VALUE 1.0UF
J 0
(-4025 4550);
DISPLAY 0.617021 (-4025 4550);
PAINT SKYBLUE (-4025 4550);
FORCEPROP 1 LAST TOLERANCE 10%
J 0
(-4025 4450);
DISPLAY 0.617021 (-4025 4450);
PAINT SKYBLUE (-4025 4450);
FORCEPROP 1 LAST VOLTAGE 6.3V
J 0
(-4025 4500);
DISPLAY 0.617021 (-4025 4500);
PAINT SKYBLUE (-4025 4500);
FORCEPROP 1 LAST MATERIAL X6S
J 0
(-4025 4400);
DISPLAY 0.617021 (-4025 4400);
PAINT SKYBLUE (-4025 4400);
FORCEPROP 1 LASTPIN (-4075 4600) $PN 1
J 0
(-4065 4580);
DISPLAY 0.617021 (-4065 4580);
PAINT ORANGE (-4065 4580);
FORCEPROP 1 LASTPIN (-4075 4400) $PN 2
J 0
(-4065 4380);
DISPLAY 0.617021 (-4065 4380);
PAINT ORANGE (-4065 4380);
FORCEPROP 1 LAST PART_NUMBER D97712-004
J 0
(-4025 4350);
DISPLAY 0.617021 (-4025 4350);
PAINT BLUE (-4025 4350);
FORCEPROP 1 LAST LOCATION C7F2
J 0
(-4025 4600);
DISPLAY 0.617021 (-4025 4600);
PAINT AQUA (-4025 4600);
FORCEPROP 2 LAST CDS_LIB dev_discrete
J 0
(-4075 4500);
PAINT ORANGE (-4075 4500);
DISPLAY INVISIBLE (-4075 4500);
FORCEPROP 2 LAST CDS_LOCATION C7F2
J 0
(-4025 4600);
DISPLAY 0.617021 (-4025 4600);
PAINT AQUA (-4025 4600);
DISPLAY INVISIBLE (-4025 4600);
FORCEPROP 2 LAST NO_XNET_CONNECTION 1
J 0
(-4025 4700);
PAINT MONO (-4025 4700);
DISPLAY INVISIBLE (-4025 4700);
FORCEPROP 2 LAST BOM_COST MIO_BIOS_MEM
J 0
(-4025 4700);
DISPLAY 1.021277 (-4025 4700);
PAINT ORANGE (-4025 4700);
DISPLAY INVISIBLE (-4025 4700);
FORCEPROP 2 LAST CDS_SEC 1
J 0
(-4025 4650);
PAINT ORANGE (-4025 4650);
DISPLAY INVISIBLE (-4025 4650);
FORCEPROP 2 LAST SEC_TYPE 0402V
J 0
(-4025 4700);
DISPLAY 1.021277 (-4025 4700);
PAINT ORANGE (-4025 4700);
DISPLAY INVISIBLE (-4025 4700);
FORCEPROP 2 LAST SEC 1
J 0
(-4025 4700);
PAINT MONO (-4025 4700);
DISPLAY INVISIBLE (-4025 4700);
FORCEPROP 1 LAST PATH I130
J 0
(-4025 4650);
DISPLAY 0.978723 (-4025 4650);
PAINT WHITE (-4025 4650);
DISPLAY INVISIBLE (-4025 4650);
FORCEPROP 2 LAST ROOM SB_SPI
J 0
(-4025 4650);
DISPLAY 1.021277 (-4025 4650);
PAINT ORANGE (-4025 4650);
DISPLAY INVISIBLE (-4025 4650);
FORCEADD CAP_A..1
(-3775 4500);
FORCEPROP 1 LASTPIN (-3775 4400) $PN 2
J 0
(-3765 4380);
DISPLAY 0.617021 (-3765 4380);
PAINT ORANGE (-3765 4380);
FORCEPROP 1 LASTPIN (-3775 4600) $PN 1
J 0
(-3765 4580);
DISPLAY 0.617021 (-3765 4580);
PAINT ORANGE (-3765 4580);
FORCEPROP 1 LAST MATERIAL X7R
J 0
(-3725 4400);
DISPLAY 0.617021 (-3725 4400);
PAINT SKYBLUE (-3725 4400);
FORCEPROP 1 LAST VOLTAGE 25V
J 0
(-3725 4500);
DISPLAY 0.617021 (-3725 4500);
PAINT SKYBLUE (-3725 4500);
FORCEPROP 1 LAST TOLERANCE 10%
J 0
(-3725 4450);
DISPLAY 0.617021 (-3725 4450);
PAINT SKYBLUE (-3725 4450);
FORCEPROP 1 LAST LOCATION C7F1
J 0
(-3725 4600);
DISPLAY 0.617021 (-3725 4600);
PAINT AQUA (-3725 4600);
FORCEPROP 1 LAST PACK_TYPE 0402V
J 0
(-3725 4300);
DISPLAY 0.617021 (-3725 4300);
PAINT SKYBLUE (-3725 4300);
FORCEPROP 1 LAST VALUE 0.01UF
J 0
(-3725 4550);
DISPLAY 0.617021 (-3725 4550);
PAINT SKYBLUE (-3725 4550);
FORCEPROP 1 LAST PART_NUMBER A36096-045
J 0
(-3725 4350);
DISPLAY 0.617021 (-3725 4350);
PAINT BLUE (-3725 4350);
FORCEPROP 2 LAST CDS_LIB dev_discrete
J 0
(-3775 4500);
PAINT ORANGE (-3775 4500);
DISPLAY INVISIBLE (-3775 4500);
FORCEPROP 2 LAST CDS_LOCATION C7F1
J 0
(-3725 4600);
DISPLAY 0.617021 (-3725 4600);
PAINT AQUA (-3725 4600);
DISPLAY INVISIBLE (-3725 4600);
FORCEPROP 2 LAST NO_XNET_CONNECTION 1
J 0
(-3725 4700);
PAINT MONO (-3725 4700);
DISPLAY INVISIBLE (-3725 4700);
FORCEPROP 2 LAST BOM_COST MIO_BIOS_MEM
J 0
(-3725 4700);
DISPLAY 1.021277 (-3725 4700);
PAINT ORANGE (-3725 4700);
DISPLAY INVISIBLE (-3725 4700);
FORCEPROP 2 LAST CDS_SEC 1
J 0
(-3725 4650);
PAINT ORANGE (-3725 4650);
DISPLAY INVISIBLE (-3725 4650);
FORCEPROP 2 LAST SEC_TYPE 0402V
J 0
(-3725 4700);
DISPLAY 1.021277 (-3725 4700);
PAINT ORANGE (-3725 4700);
DISPLAY INVISIBLE (-3725 4700);
FORCEPROP 2 LAST SEC 1
J 0
(-3725 4700);
PAINT MONO (-3725 4700);
DISPLAY INVISIBLE (-3725 4700);
FORCEPROP 1 LAST PATH I131
J 0
(-3725 4650);
DISPLAY 0.978723 (-3725 4650);
PAINT WHITE (-3725 4650);
DISPLAY INVISIBLE (-3725 4650);
FORCEPROP 2 LAST ROOM SB_SPI
J 0
(-3725 4650);
DISPLAY 1.021277 (-3725 4650);
PAINT ORANGE (-3725 4650);
DISPLAY INVISIBLE (-3725 4650);
FORCEADD GND..1
(-3775 4175);
FORCEPROP 3 LASTPIN (-3775 4225) SIG_NAME GND\g
J 0
(-3765 4235);
DISPLAY 0.659574 (-3765 4235);
PAINT MONO (-3765 4235);
DISPLAY INVISIBLE (-3765 4235);
FORCEPROP 1 LAST BODY_TYPE PLUMBING
J 0
(-3820 4132);
DISPLAY 0.340426 (-3820 4132);
PAINT GREEN (-3820 4132);
DISPLAY INVISIBLE (-3820 4132);
FORCEPROP 2 LAST CDS_LIB mstr_symbols
J 0
(-3775 4175);
PAINT ORANGE (-3775 4175);
DISPLAY INVISIBLE (-3775 4175);
FORCEPROP 1 LAST VOLTAGE 0.0V
J 0
(-3820 4132);
DISPLAY 0.340426 (-3820 4132);
PAINT SKYBLUE (-3820 4132);
DISPLAY INVISIBLE (-3820 4132);
FORCEPROP 1 LAST SIZE 1B
J 0
(-3700 4125);
DISPLAY 0.872340 (-3700 4125);
PAINT AQUA (-3700 4125);
DISPLAY INVISIBLE (-3700 4125);
FORCEPROP 1 LAST PATH I133
J 0
(-3700 4175);
DISPLAY 0.872340 (-3700 4175);
PAINT AQUA (-3700 4175);
DISPLAY INVISIBLE (-3700 4175);
FORCEPROP 1 LAST HDL_POWER GND
J 0
(-3775 4325);
DISPLAY 0.872340 (-3775 4325);
PAINT GREEN (-3775 4325);
DISPLAY INVISIBLE (-3775 4325);
FORCEADD CAP_A..1
(-3625 2400);
FORCEPROP 1 LASTPIN (-3625 2300) $PN 2
J 0
(-3615 2280);
DISPLAY 0.617021 (-3615 2280);
PAINT ORANGE (-3615 2280);
FORCEPROP 1 LASTPIN (-3625 2500) $PN 1
J 0
(-3615 2480);
DISPLAY 0.617021 (-3615 2480);
PAINT ORANGE (-3615 2480);
FORCEPROP 1 LAST MATERIAL X7R
J 0
(-3575 2300);
DISPLAY 0.617021 (-3575 2300);
PAINT SKYBLUE (-3575 2300);
FORCEPROP 1 LAST VOLTAGE 25V
J 0
(-3575 2400);
DISPLAY 0.617021 (-3575 2400);
PAINT SKYBLUE (-3575 2400);
FORCEPROP 1 LAST PACK_TYPE 0402V
J 0
(-3575 2200);
DISPLAY 0.617021 (-3575 2200);
PAINT SKYBLUE (-3575 2200);
FORCEPROP 1 LAST TOLERANCE 10%
J 0
(-3575 2350);
DISPLAY 0.617021 (-3575 2350);
PAINT SKYBLUE (-3575 2350);
FORCEPROP 1 LAST LOCATION C3T5
J 0
(-3575 2500);
DISPLAY 0.617021 (-3575 2500);
PAINT AQUA (-3575 2500);
FORCEPROP 1 LAST PART_NUMBER A36096-045
J 0
(-3575 2250);
DISPLAY 0.617021 (-3575 2250);
PAINT BLUE (-3575 2250);
FORCEPROP 1 LAST VALUE 0.01UF
J 0
(-3575 2450);
DISPLAY 0.617021 (-3575 2450);
PAINT SKYBLUE (-3575 2450);
FORCEPROP 2 LAST CDS_LIB dev_discrete
J 0
(-3625 2400);
PAINT ORANGE (-3625 2400);
DISPLAY INVISIBLE (-3625 2400);
FORCEPROP 2 LAST CDS_LOCATION C3T5
J 0
(-3575 2500);
DISPLAY 0.617021 (-3575 2500);
PAINT AQUA (-3575 2500);
DISPLAY INVISIBLE (-3575 2500);
FORCEPROP 2 LAST ROOM SB_SPI
J 0
(-3575 2550);
DISPLAY 1.021277 (-3575 2550);
PAINT ORANGE (-3575 2550);
DISPLAY INVISIBLE (-3575 2550);
FORCEPROP 1 LAST PATH I136
J 0
(-3575 2550);
DISPLAY 0.978723 (-3575 2550);
PAINT WHITE (-3575 2550);
DISPLAY INVISIBLE (-3575 2550);
FORCEPROP 2 LAST CDS_SEC 1
J 0
(-3575 2550);
PAINT ORANGE (-3575 2550);
DISPLAY INVISIBLE (-3575 2550);
FORCEPROP 2 LAST BOM_COST MIO_BIOS_MEM
J 0
(-3575 2600);
DISPLAY 1.021277 (-3575 2600);
PAINT ORANGE (-3575 2600);
DISPLAY INVISIBLE (-3575 2600);
FORCEPROP 2 LAST NO_XNET_CONNECTION 1
J 0
(-3575 2600);
PAINT MONO (-3575 2600);
DISPLAY INVISIBLE (-3575 2600);
FORCEPROP 2 LAST SEC_TYPE 0402V
J 0
(-3575 2600);
DISPLAY 1.021277 (-3575 2600);
PAINT ORANGE (-3575 2600);
DISPLAY INVISIBLE (-3575 2600);
FORCEPROP 2 LAST SEC 1
J 0
(-3575 2600);
PAINT MONO (-3575 2600);
DISPLAY INVISIBLE (-3575 2600);
FORCEADD CAP_A..1
(-3925 2400);
FORCEPROP 1 LAST MATERIAL X6S
J 0
(-3875 2300);
DISPLAY 0.617021 (-3875 2300);
PAINT SKYBLUE (-3875 2300);
FORCEPROP 1 LAST VOLTAGE 6.3V
J 0
(-3875 2400);
DISPLAY 0.617021 (-3875 2400);
PAINT SKYBLUE (-3875 2400);
FORCEPROP 1 LAST PACK_TYPE 0402V
J 0
(-3875 2200);
DISPLAY 0.617021 (-3875 2200);
PAINT SKYBLUE (-3875 2200);
FORCEPROP 1 LAST TOLERANCE 10%
J 0
(-3875 2350);
DISPLAY 0.617021 (-3875 2350);
PAINT SKYBLUE (-3875 2350);
FORCEPROP 1 LAST VALUE 1.0UF
J 0
(-3875 2450);
DISPLAY 0.617021 (-3875 2450);
PAINT SKYBLUE (-3875 2450);
FORCEPROP 1 LAST PART_NUMBER D97712-004
J 0
(-3875 2250);
DISPLAY 0.617021 (-3875 2250);
PAINT BLUE (-3875 2250);
FORCEPROP 1 LAST LOCATION C3T4
J 0
(-3875 2500);
DISPLAY 0.617021 (-3875 2500);
PAINT AQUA (-3875 2500);
FORCEPROP 1 LASTPIN (-3925 2300) $PN 2
J 0
(-3915 2280);
DISPLAY 0.787234 (-3915 2280);
PAINT ORANGE (-3915 2280);
DISPLAY INVISIBLE (-3915 2280);
FORCEPROP 2 LAST CDS_LOCATION C3T4
J 0
(-3875 2500);
DISPLAY 0.617021 (-3875 2500);
PAINT AQUA (-3875 2500);
DISPLAY INVISIBLE (-3875 2500);
FORCEPROP 2 LAST CDS_LIB dev_discrete
J 0
(-3925 2400);
PAINT ORANGE (-3925 2400);
DISPLAY INVISIBLE (-3925 2400);
FORCEPROP 1 LASTPIN (-3925 2500) $PN 1
J 0
(-3915 2480);
DISPLAY 0.787234 (-3915 2480);
PAINT ORANGE (-3915 2480);
DISPLAY INVISIBLE (-3915 2480);
FORCEPROP 2 LAST ROOM SB_SPI
J 0
(-3875 2550);
DISPLAY 1.021277 (-3875 2550);
PAINT ORANGE (-3875 2550);
DISPLAY INVISIBLE (-3875 2550);
FORCEPROP 1 LAST PATH I138
J 0
(-3875 2550);
DISPLAY 0.978723 (-3875 2550);
PAINT WHITE (-3875 2550);
DISPLAY INVISIBLE (-3875 2550);
FORCEPROP 2 LAST $SEC 1
J 0
(-3875 2600);
PAINT MONO (-3875 2600);
DISPLAY INVISIBLE (-3875 2600);
FORCEPROP 2 LAST CDS_SEC 1
J 0
(-3875 2600);
PAINT MONO (-3875 2600);
DISPLAY INVISIBLE (-3875 2600);
FORCEPROP 2 LAST BOM_COST MIO_BIOS_MEM
J 0
(-3875 2600);
DISPLAY 1.021277 (-3875 2600);
PAINT ORANGE (-3875 2600);
DISPLAY INVISIBLE (-3875 2600);
FORCEPROP 2 LAST NO_XNET_CONNECTION 1
J 0
(-3875 2600);
PAINT MONO (-3875 2600);
DISPLAY INVISIBLE (-3875 2600);
FORCEADD GND..1
(-3625 2100);
FORCEPROP 3 LASTPIN (-3625 2150) SIG_NAME GND\g
J 0
(-3615 2160);
DISPLAY 0.659574 (-3615 2160);
PAINT MONO (-3615 2160);
DISPLAY INVISIBLE (-3615 2160);
FORCEPROP 1 LAST BODY_TYPE PLUMBING
J 0
(-3670 2057);
DISPLAY 0.340426 (-3670 2057);
PAINT GREEN (-3670 2057);
DISPLAY INVISIBLE (-3670 2057);
FORCEPROP 2 LAST CDS_LIB mstr_symbols
J 0
(-3625 2100);
PAINT ORANGE (-3625 2100);
DISPLAY INVISIBLE (-3625 2100);
FORCEPROP 1 LAST VOLTAGE 0.0V
J 0
(-3670 2057);
DISPLAY 0.340426 (-3670 2057);
PAINT SKYBLUE (-3670 2057);
DISPLAY INVISIBLE (-3670 2057);
FORCEPROP 1 LAST HDL_POWER GND
J 0
(-3625 2250);
DISPLAY 0.872340 (-3625 2250);
PAINT GREEN (-3625 2250);
DISPLAY INVISIBLE (-3625 2250);
FORCEPROP 1 LAST SIZE 1B
J 0
(-3550 2050);
DISPLAY 0.872340 (-3550 2050);
PAINT AQUA (-3550 2050);
DISPLAY INVISIBLE (-3550 2050);
FORCEPROP 1 LAST PATH I139
J 0
(-3550 2100);
DISPLAY 0.872340 (-3550 2100);
PAINT AQUA (-3550 2100);
DISPLAY INVISIBLE (-3550 2100);
FORCEADD RES..1
(-1450 4425);
FORCEPROP 1 LAST TOLERANCE 1%
J 0
(-1650 4375);
DISPLAY 0.617021 (-1650 4375);
PAINT SKYBLUE (-1650 4375);
FORCEPROP 1 LASTPIN (-1550 4425) $PN 1
J 0
(-1538 4437);
DISPLAY 0.617021 (-1538 4437);
PAINT ORANGE (-1538 4437);
FORCEPROP 1 LAST VALUE 10.0K
J 2
(-1475 4375);
DISPLAY 0.617021 (-1475 4375);
PAINT SKYBLUE (-1475 4375);
FORCEPROP 1 LAST PART_NUMBER G21796-016
J 0
(-1550 4325);
DISPLAY 0.617021 (-1550 4325);
PAINT BLUE (-1550 4325);
FORCEPROP 1 LAST WATTAGE 1/16W
J 2
(-1300 4375);
DISPLAY 0.617021 (-1300 4375);
PAINT SKYBLUE (-1300 4375);
FORCEPROP 1 LAST LOCATION R7F32
J 0
(-1475 4475);
DISPLAY 0.617021 (-1475 4475);
PAINT AQUA (-1475 4475);
FORCEPROP 1 LASTPIN (-1350 4425) $PN 2
J 0
(-1388 4437);
DISPLAY 0.617021 (-1388 4437);
PAINT ORANGE (-1388 4437);
FORCEPROP 1 LAST PACK_TYPE 0402
J 0
(-1150 4375);
DISPLAY 0.617021 (-1150 4375);
PAINT SKYBLUE (-1150 4375);
FORCEPROP 1 LAST MATERIAL CHIP
J 0
(-1275 4375);
DISPLAY 0.617021 (-1275 4375);
PAINT SKYBLUE (-1275 4375);
FORCEPROP 2 LAST CDS_LOCATION R7F32
J 0
(-1475 4475);
DISPLAY 0.617021 (-1475 4475);
PAINT AQUA (-1475 4475);
DISPLAY INVISIBLE (-1475 4475);
FORCEPROP 2 LAST ROOM SB_SPI
J 0
(-1475 4525);
DISPLAY 1.021277 (-1475 4525);
PAINT ORANGE (-1475 4525);
DISPLAY INVISIBLE (-1475 4525);
FORCEPROP 2 LAST CDS_LIB mstr_discrete
J 0
(-1450 4425);
PAINT ORANGE (-1450 4425);
DISPLAY INVISIBLE (-1450 4425);
FORCEPROP 2 LAST BOM_COST MIO_BIOS_MEM
J 0
(-1475 4575);
DISPLAY 1.021277 (-1475 4575);
PAINT ORANGE (-1475 4575);
DISPLAY INVISIBLE (-1475 4575);
FORCEPROP 1 LAST PATH I140
J 0
(-1500 4575);
DISPLAY 0.978723 (-1500 4575);
PAINT WHITE (-1500 4575);
DISPLAY INVISIBLE (-1500 4575);
FORCEPROP 2 LAST SEC_TYPE 0402
J 0
(-1500 4625);
DISPLAY 1.021277 (-1500 4625);
PAINT ORANGE (-1500 4625);
DISPLAY INVISIBLE (-1500 4625);
FORCEPROP 2 LAST SEC 1
J 0
(-1500 4625);
PAINT MONO (-1500 4625);
DISPLAY INVISIBLE (-1500 4625);
FORCEPROP 2 LAST NO_XNET_CONNECTION 1
J 0
(-1500 4625);
PAINT MONO (-1500 4625);
DISPLAY INVISIBLE (-1500 4625);
FORCEADD P3V3_STBY..1
(-1750 4625);
FORCEPROP 3 LASTPIN (-1750 4575) SIG_NAME P3V3_STBY\g
J 0
(-1740 4585);
DISPLAY 0.659574 (-1740 4585);
PAINT MONO (-1740 4585);
DISPLAY INVISIBLE (-1740 4585);
FORCEPROP 1 LAST HDL_POWER P3V3_STBY
J 0
(-2050 4500);
DISPLAY 0.872340 (-2050 4500);
PAINT ORANGE (-2050 4500);
DISPLAY INVISIBLE (-2050 4500);
FORCEPROP 1 LAST BODY_TYPE PLUMBING
J 0
(-1795 4582);
DISPLAY 0.340426 (-1795 4582);
PAINT GREEN (-1795 4582);
DISPLAY INVISIBLE (-1795 4582);
FORCEPROP 1 LAST VOLTAGE 3.3V
J 0
(-1795 4582);
DISPLAY 0.340426 (-1795 4582);
PAINT SKYBLUE (-1795 4582);
DISPLAY INVISIBLE (-1795 4582);
FORCEPROP 1 LAST PATH I141
J 0
(-1705 4627);
DISPLAY 0.340426 (-1705 4627);
PAINT GREEN (-1705 4627);
DISPLAY INVISIBLE (-1705 4627);
FORCEPROP 2 LAST CDS_LIB mstr_symbols
J 0
(-1750 4625);
PAINT ORANGE (-1750 4625);
DISPLAY INVISIBLE (-1750 4625);
FORCEPROP 1 LAST SIZE 1B
J 0
(-1705 4647);
DISPLAY 0.340426 (-1705 4647);
PAINT GREEN (-1705 4647);
DISPLAY INVISIBLE (-1705 4647);
FORCEADD OFFPAGE..2
(-675 4425);
FORCEPROP 2 LAST $XR0 153 
J 0
(-486 4425);
DISPLAY 0.638298 (-486 4425);
PAINT MONO (-486 4425);
FORCEPROP 1 LAST COMMENT_BODY TRUE
J 0
(-720 4330);
DISPLAY 0.872340 (-720 4330);
PAINT GREEN (-720 4330);
DISPLAY INVISIBLE (-720 4330);
FORCEPROP 2 LAST CDS_LIB mstr_standard
J 0
(-675 4425);
PAINT ORANGE (-675 4425);
DISPLAY INVISIBLE (-675 4425);
FORCEPROP 2 LAST PATH I144
J 0
(-625 4500);
DISPLAY 1.021277 (-625 4500);
PAINT ORANGE (-625 4500);
DISPLAY INVISIBLE (-625 4500);
FORCEPROP 1 LAST OFFPAGE TRUE
J 0
(-350 4300);
DISPLAY 0.872340 (-350 4300);
PAINT GREEN (-350 4300);
DISPLAY INVISIBLE (-350 4300);
FORCEADD W25Q256..1
(-4900 3975);
FORCEPROP 2 LASTPIN (-5450 3675) $PN 3
J 2
(-5460 3685);
DISPLAY 0.617021 (-5460 3685);
PAINT ORANGE (-5460 3685);
FORCEPROP 2 LASTPIN (-5450 3725) $PN 7
J 2
(-5460 3735);
DISPLAY 0.617021 (-5460 3735);
PAINT ORANGE (-5460 3735);
FORCEPROP 2 LASTPIN (-5450 3825) $PN 16
J 2
(-5460 3835);
DISPLAY 0.617021 (-5460 3835);
PAINT ORANGE (-5460 3835);
FORCEPROP 2 LASTPIN (-5450 3925) $PN 15
J 2
(-5460 3935);
DISPLAY 0.617021 (-5460 3935);
PAINT ORANGE (-5460 3935);
FORCEPROP 2 LASTPIN (-5450 3975) $PN 8
J 2
(-5460 3985);
DISPLAY 0.617021 (-5460 3985);
PAINT ORANGE (-5460 3985);
FORCEPROP 2 LASTPIN (-5450 4025) $PN 9
J 2
(-5460 4035);
DISPLAY 0.617021 (-5460 4035);
PAINT ORANGE (-5460 4035);
FORCEPROP 1 LAST PART_NUMBER H25002-001
J 0
(-5400 3475);
DISPLAY 0.617021 (-5400 3475);
PAINT BLUE (-5400 3475);
FORCEPROP 2 LASTPIN (-4350 3725) $PN 10
J 0
(-4340 3735);
DISPLAY 0.617021 (-4340 3735);
PAINT ORANGE (-4340 3735);
FORCEPROP 2 LASTPIN (-4350 3875) $PN 14
J 0
(-4340 3885);
DISPLAY 0.617021 (-4340 3885);
PAINT ORANGE (-4340 3885);
FORCEPROP 2 LASTPIN (-4350 3925) $PN 13
J 0
(-4340 3935);
DISPLAY 0.617021 (-4340 3935);
PAINT ORANGE (-4340 3935);
FORCEPROP 2 LASTPIN (-4350 3975) $PN 12
J 0
(-4340 3985);
DISPLAY 0.617021 (-4340 3985);
PAINT ORANGE (-4340 3985);
FORCEPROP 2 LASTPIN (-4350 4025) $PN 11
J 0
(-4340 4035);
DISPLAY 0.617021 (-4340 4035);
PAINT ORANGE (-4340 4035);
FORCEPROP 2 LASTPIN (-5450 4075) $PN 1
J 2
(-5460 4085);
DISPLAY 0.617021 (-5460 4085);
PAINT ORANGE (-5460 4085);
FORCEPROP 2 LASTPIN (-4350 4075) $PN 6
J 0
(-4340 4085);
DISPLAY 0.617021 (-4340 4085);
PAINT ORANGE (-4340 4085);
FORCEPROP 1 LAST MATERIAL IC
J 0
(-5400 4375);
DISPLAY 0.617021 (-5400 4375);
PAINT SKYBLUE (-5400 4375);
FORCEPROP 2 LASTPIN (-5450 4175) $PN 2
J 2
(-5460 4185);
DISPLAY 0.617021 (-5460 4185);
PAINT ORANGE (-5460 4185);
FORCEPROP 1 LAST LOCATION U7F1
J 0
(-5225 4375);
DISPLAY 0.617021 (-5225 4375);
PAINT AQUA (-5225 4375);
FORCEPROP 2 LASTPIN (-4350 4125) $PN 5
J 0
(-4340 4135);
DISPLAY 0.617021 (-4340 4135);
PAINT ORANGE (-4340 4135);
FORCEPROP 2 LASTPIN (-4350 4175) $PN 4
J 0
(-4340 4185);
DISPLAY 0.617021 (-4340 4185);
PAINT ORANGE (-4340 4185);
FORCEPROP 2 LAST CDS_LIB mstr_memory
J 0
(-4900 3975);
PAINT MONO (-4900 3975);
DISPLAY INVISIBLE (-4900 3975);
FORCEPROP 1 LAST PACK_TYPE XSOI
J 0
(-5400 4475);
PAINT SKYBLUE (-5400 4475);
DISPLAY INVISIBLE (-5400 4475);
FORCEPROP 2 LAST BOM_COST MIO_BIOS_MEM
J 0
(-5400 4475);
DISPLAY 1.021277 (-5400 4475);
PAINT ORANGE (-5400 4475);
DISPLAY INVISIBLE (-5400 4475);
FORCEPROP 2 LAST CDS_LOCATION U7F1
J 0
(-5225 4375);
DISPLAY 0.617021 (-5225 4375);
PAINT AQUA (-5225 4375);
DISPLAY INVISIBLE (-5225 4375);
FORCEPROP 2 LAST ROOM SB_SPI
J 0
(-5400 4425);
DISPLAY 1.021277 (-5400 4425);
PAINT ORANGE (-5400 4425);
DISPLAY INVISIBLE (-5400 4425);
FORCEPROP 1 LAST PATH I146
J 0
(-4900 4375);
PAINT GREEN (-4900 4375);
DISPLAY INVISIBLE (-4900 4375);
FORCEPROP 2 LAST SEC 1
J 0
(-4900 4425);
DISPLAY 0.680851 (-4900 4425);
PAINT MONO (-4900 4425);
DISPLAY INVISIBLE (-4900 4425);
FORCEPROP 2 LAST SEC_TYPE XSOI
J 0
(-4900 4425);
DISPLAY 1.021277 (-4900 4425);
PAINT ORANGE (-4900 4425);
DISPLAY INVISIBLE (-4900 4425);
FORCEADD RES..2
R 2
(-5875 2325);
FORCEPROP 1 LAST PART_NUMBER G21796-072
J 2
(-5915 2200);
DISPLAY 0.617021 (-5915 2200);
PAINT BLUE (-5915 2200);
FORCEPROP 1 LAST WATTAGE 1/16W
J 2
(-5915 2250);
DISPLAY 0.617021 (-5915 2250);
PAINT SKYBLUE (-5915 2250);
FORCEPROP 1 LAST PACK_TYPE 0402
J 2
(-5915 2150);
DISPLAY 0.617021 (-5915 2150);
PAINT SKYBLUE (-5915 2150);
FORCEPROP 1 LAST TOLERANCE 1%
J 2
(-5920 2300);
DISPLAY 0.617021 (-5920 2300);
PAINT SKYBLUE (-5920 2300);
FORCEPROP 1 LAST VALUE 4.75K
J 2
(-5920 2400);
DISPLAY 0.617021 (-5920 2400);
PAINT SKYBLUE (-5920 2400);
FORCEPROP 1 LAST MATERIAL EMPTY
J 2
(-5915 2350);
DISPLAY 0.617021 (-5915 2350);
PAINT RED (-5915 2350);
FORCEPROP 1 LAST LOCATION R3T3
J 2
(-5920 2450);
DISPLAY 0.617021 (-5920 2450);
PAINT AQUA (-5920 2450);
FORCEPROP 1 LASTPIN (-5875 2425) $PN 1
J 2
(-5880 2387);
DISPLAY 0.617021 (-5880 2387);
PAINT ORANGE (-5880 2387);
FORCEPROP 1 LASTPIN (-5875 2225) $PN 2
J 2
(-5880 2235);
DISPLAY 0.617021 (-5880 2235);
PAINT ORANGE (-5880 2235);
FORCEPROP 2 LAST CDS_LOCATION R3T3
J 2
(-5920 2450);
DISPLAY 0.617021 (-5920 2450);
PAINT AQUA (-5920 2450);
DISPLAY INVISIBLE (-5920 2450);
FORCEPROP 1 LAST PATH I150
J 2
(-5925 2500);
DISPLAY 0.978723 (-5925 2500);
PAINT WHITE (-5925 2500);
DISPLAY INVISIBLE (-5925 2500);
FORCEPROP 2 LAST ROOM SB_SPI
J 0
(-5900 2500);
DISPLAY 1.021277 (-5900 2500);
PAINT ORANGE (-5900 2500);
DISPLAY INVISIBLE (-5900 2500);
FORCEPROP 2 LAST CDS_LIB mstr_discrete
J 0
(-5875 2325);
PAINT ORANGE (-5875 2325);
DISPLAY INVISIBLE (-5875 2325);
FORCEPROP 2 LAST NO_XNET_CONNECTION 1
J 0
(-5925 2550);
PAINT MONO (-5925 2550);
DISPLAY INVISIBLE (-5925 2550);
FORCEPROP 2 LAST SEC 1
J 0
(-5925 2550);
DISPLAY 0.680851 (-5925 2550);
PAINT MONO (-5925 2550);
DISPLAY INVISIBLE (-5925 2550);
FORCEPROP 2 LAST BOM_COST MIO_BIOS_MEM
J 0
(-5900 2550);
DISPLAY 1.021277 (-5900 2550);
PAINT ORANGE (-5900 2550);
DISPLAY INVISIBLE (-5900 2550);
FORCEPROP 2 LAST SEC_TYPE 0402
J 0
(-5925 2550);
DISPLAY 1.021277 (-5925 2550);
PAINT ORANGE (-5925 2550);
DISPLAY INVISIBLE (-5925 2550);
FORCEADD P3V3_STBY..1
(-6375 2725);
FORCEPROP 3 LASTPIN (-6375 2675) SIG_NAME P3V3_STBY\g
J 0
(-6365 2685);
DISPLAY 0.659574 (-6365 2685);
PAINT MONO (-6365 2685);
DISPLAY INVISIBLE (-6365 2685);
FORCEPROP 1 LAST HDL_POWER P3V3_STBY
J 0
(-6675 2600);
DISPLAY 0.872340 (-6675 2600);
PAINT ORANGE (-6675 2600);
DISPLAY INVISIBLE (-6675 2600);
FORCEPROP 1 LAST PATH I151
J 0
(-6330 2727);
DISPLAY 0.340426 (-6330 2727);
PAINT GREEN (-6330 2727);
DISPLAY INVISIBLE (-6330 2727);
FORCEPROP 1 LAST BODY_TYPE PLUMBING
J 0
(-6420 2682);
DISPLAY 0.340426 (-6420 2682);
PAINT GREEN (-6420 2682);
DISPLAY INVISIBLE (-6420 2682);
FORCEPROP 2 LAST CDS_LIB mstr_symbols
J 0
(-6375 2725);
PAINT ORANGE (-6375 2725);
DISPLAY INVISIBLE (-6375 2725);
FORCEPROP 1 LAST SIZE 1B
J 0
(-6330 2747);
DISPLAY 0.340426 (-6330 2747);
PAINT GREEN (-6330 2747);
DISPLAY INVISIBLE (-6330 2747);
FORCEPROP 1 LAST VOLTAGE 3.3V
J 0
(-6420 2682);
DISPLAY 0.340426 (-6420 2682);
PAINT SKYBLUE (-6420 2682);
DISPLAY INVISIBLE (-6420 2682);
FORCEADD RES..2
R 2
(-6175 2325);
FORCEPROP 1 LAST PART_NUMBER G21796-072
J 2
(-6215 2200);
DISPLAY 0.617021 (-6215 2200);
PAINT BLUE (-6215 2200);
FORCEPROP 1 LASTPIN (-6175 2225) $PN 2
J 2
(-6180 2235);
DISPLAY 0.617021 (-6180 2235);
PAINT ORANGE (-6180 2235);
FORCEPROP 1 LAST WATTAGE 1/16W
J 2
(-6215 2250);
DISPLAY 0.617021 (-6215 2250);
PAINT SKYBLUE (-6215 2250);
FORCEPROP 1 LAST PACK_TYPE 0402
J 2
(-6215 2150);
DISPLAY 0.617021 (-6215 2150);
PAINT SKYBLUE (-6215 2150);
FORCEPROP 1 LAST TOLERANCE 1%
J 2
(-6220 2300);
DISPLAY 0.617021 (-6220 2300);
PAINT SKYBLUE (-6220 2300);
FORCEPROP 1 LAST LOCATION R3T5
J 2
(-6220 2450);
DISPLAY 0.617021 (-6220 2450);
PAINT AQUA (-6220 2450);
FORCEPROP 1 LAST VALUE 4.75K
J 2
(-6220 2400);
DISPLAY 0.617021 (-6220 2400);
PAINT SKYBLUE (-6220 2400);
FORCEPROP 1 LAST MATERIAL CHIP
J 2
(-6215 2350);
DISPLAY 0.617021 (-6215 2350);
PAINT SKYBLUE (-6215 2350);
FORCEPROP 1 LASTPIN (-6175 2425) $PN 1
J 2
(-6180 2387);
DISPLAY 0.617021 (-6180 2387);
PAINT ORANGE (-6180 2387);
FORCEPROP 2 LAST CDS_LIB mstr_discrete
J 0
(-6175 2325);
PAINT ORANGE (-6175 2325);
DISPLAY INVISIBLE (-6175 2325);
FORCEPROP 2 LAST ROOM SB_SPI
J 0
(-6200 2500);
DISPLAY 1.021277 (-6200 2500);
PAINT ORANGE (-6200 2500);
DISPLAY INVISIBLE (-6200 2500);
FORCEPROP 1 LAST PATH I152
J 2
(-6225 2500);
DISPLAY 0.978723 (-6225 2500);
PAINT WHITE (-6225 2500);
DISPLAY INVISIBLE (-6225 2500);
FORCEPROP 2 LAST CDS_LOCATION R3T5
J 2
(-6220 2450);
DISPLAY 0.617021 (-6220 2450);
PAINT AQUA (-6220 2450);
DISPLAY INVISIBLE (-6220 2450);
FORCEPROP 2 LAST NO_XNET_CONNECTION 1
J 0
(-6225 2550);
PAINT MONO (-6225 2550);
DISPLAY INVISIBLE (-6225 2550);
FORCEPROP 2 LAST SEC 1
J 0
(-6225 2550);
DISPLAY 0.680851 (-6225 2550);
PAINT MONO (-6225 2550);
DISPLAY INVISIBLE (-6225 2550);
FORCEPROP 2 LAST BOM_COST MIO_BIOS_MEM
J 0
(-6200 2550);
DISPLAY 1.021277 (-6200 2550);
PAINT ORANGE (-6200 2550);
DISPLAY INVISIBLE (-6200 2550);
FORCEPROP 2 LAST SEC_TYPE 0402
J 0
(-6225 2550);
DISPLAY 1.021277 (-6225 2550);
PAINT ORANGE (-6225 2550);
DISPLAY INVISIBLE (-6225 2550);
FORCEADD OFFPAGE..1
(-7075 1975);
FORCEPROP 2 LAST $XR0 153 
J 0
(-7357 1975);
DISPLAY 0.638298 (-7357 1975);
PAINT MONO (-7357 1975);
FORCEPROP 2 LAST CDS_LIB mstr_standard
J 0
(-7075 1975);
PAINT ORANGE (-7075 1975);
DISPLAY INVISIBLE (-7075 1975);
FORCEPROP 1 LAST COMMENT_BODY TRUE
J 0
(-6950 1875);
DISPLAY 0.872340 (-6950 1875);
PAINT GREEN (-6950 1875);
DISPLAY INVISIBLE (-6950 1875);
FORCEPROP 1 LAST OFFPAGE TRUE
J 0
(-6750 1850);
DISPLAY 0.872340 (-6750 1850);
PAINT GREEN (-6750 1850);
DISPLAY INVISIBLE (-6750 1850);
FORCEPROP 2 LAST PATH I153
J 0
(-7325 2025);
DISPLAY 1.021277 (-7325 2025);
PAINT ORANGE (-7325 2025);
DISPLAY INVISIBLE (-7325 2025);
FORCEADD GND..1
(-4075 1500);
FORCEPROP 3 LASTPIN (-4075 1550) SIG_NAME GND\g
J 0
(-4065 1560);
DISPLAY 0.659574 (-4065 1560);
PAINT MONO (-4065 1560);
DISPLAY INVISIBLE (-4065 1560);
FORCEPROP 1 LAST BODY_TYPE PLUMBING
J 0
(-4120 1457);
DISPLAY 0.340426 (-4120 1457);
PAINT GREEN (-4120 1457);
DISPLAY INVISIBLE (-4120 1457);
FORCEPROP 1 LAST SIZE 1B
J 0
(-4000 1450);
DISPLAY 1.170213 (-4000 1450);
PAINT GREEN (-4000 1450);
DISPLAY INVISIBLE (-4000 1450);
FORCEPROP 1 LAST VOLTAGE 0
J 0
(-4075 1500);
PAINT SKYBLUE (-4075 1500);
DISPLAY INVISIBLE (-4075 1500);
FORCEPROP 2 LAST CDS_LIB mstr_symbols
J 0
(-4075 1500);
PAINT ORANGE (-4075 1500);
DISPLAY INVISIBLE (-4075 1500);
FORCEPROP 1 LAST PATH I154
J 0
(-4000 1500);
DISPLAY 0.872340 (-4000 1500);
PAINT AQUA (-4000 1500);
DISPLAY INVISIBLE (-4000 1500);
FORCEPROP 1 LAST HDL_POWER GND
J 0
(-4075 1650);
DISPLAY 1.170213 (-4075 1650);
PAINT GREEN (-4075 1650);
DISPLAY INVISIBLE (-4075 1650);
FORCEADD RES..1
(-6200 1875);
FORCEPROP 1 LASTPIN (-6300 1875) $PN 1
J 0
(-6288 1887);
DISPLAY 0.617021 (-6288 1887);
PAINT MONO (-6288 1887);
FORCEPROP 1 LASTPIN (-6100 1875) $PN 2
J 0
(-6138 1887);
DISPLAY 0.617021 (-6138 1887);
PAINT MONO (-6138 1887);
FORCEPROP 1 LAST VALUE 33.2
J 2
(-5975 1882);
DISPLAY 0.617021 (-5975 1882);
PAINT SKYBLUE (-5975 1882);
FORCEPROP 1 LAST LOCATION R3T2
J 0
(-6107 1832);
DISPLAY 0.617021 (-6107 1832);
PAINT AQUA (-6107 1832);
FORCEPROP 1 LAST WATTAGE 1/16W
J 2
(-6225 1725);
PAINT SKYBLUE (-6225 1725);
DISPLAY INVISIBLE (-6225 1725);
FORCEPROP 2 LAST CDS_LIB mstr_discrete
J 1
(-6200 1875);
PAINT ORANGE (-6200 1875);
DISPLAY INVISIBLE (-6200 1875);
FORCEPROP 1 LAST PART_NUMBER G21796-074
J 0
(-6250 1975);
PAINT BLUE (-6250 1975);
DISPLAY INVISIBLE (-6250 1975);
FORCEPROP 1 LAST PATH I155
J 0
(-6250 2025);
DISPLAY 0.978723 (-6250 2025);
PAINT WHITE (-6250 2025);
DISPLAY INVISIBLE (-6250 2025);
FORCEPROP 2 LAST SEC_TYPE 0402
J 0
(-6250 2100);
DISPLAY 1.021277 (-6250 2100);
PAINT ORANGE (-6250 2100);
DISPLAY INVISIBLE (-6250 2100);
FORCEPROP 2 LAST SEC 1
J 0
(-6250 2100);
DISPLAY 0.680851 (-6250 2100);
PAINT MONO (-6250 2100);
DISPLAY INVISIBLE (-6250 2100);
FORCEPROP 1 LAST TOLERANCE 1%
J 0
(-6125 1725);
PAINT SKYBLUE (-6125 1725);
DISPLAY INVISIBLE (-6125 1725);
FORCEPROP 1 LAST PACK_TYPE 0402
J 0
(-5950 1725);
PAINT SKYBLUE (-5950 1725);
DISPLAY INVISIBLE (-5950 1725);
FORCEPROP 2 LAST CDS_LOCATION R3T2
J 0
(-6107 1832);
DISPLAY 0.617021 (-6107 1832);
PAINT AQUA (-6107 1832);
DISPLAY INVISIBLE (-6107 1832);
FORCEPROP 2 LAST ROOM SB_SPI
J 0
(-5975 1925);
DISPLAY 1.021277 (-5975 1925);
PAINT ORANGE (-5975 1925);
DISPLAY INVISIBLE (-5975 1925);
FORCEPROP 2 LAST BOM_COST MIO_BIOS_MEM
J 0
(-5975 1975);
DISPLAY 1.021277 (-5975 1975);
PAINT ORANGE (-5975 1975);
DISPLAY INVISIBLE (-5975 1975);
FORCEPROP 1 LAST MATERIAL CHIP
J 0
(-6000 1875);
PAINT SKYBLUE (-6000 1875);
DISPLAY INVISIBLE (-6000 1875);
FORCEADD RES..1
(-6425 1500);
FORCEPROP 1 LAST WATTAGE 1/16W
J 2
(-6625 1425);
DISPLAY 0.617021 (-6625 1425);
PAINT SKYBLUE (-6625 1425);
FORCEPROP 1 LAST VALUE 33.2
J 2
(-6500 1425);
DISPLAY 0.617021 (-6500 1425);
PAINT SKYBLUE (-6500 1425);
FORCEPROP 1 LAST TOLERANCE 1%
J 0
(-6400 1425);
DISPLAY 0.617021 (-6400 1425);
PAINT SKYBLUE (-6400 1425);
FORCEPROP 1 LAST PART_NUMBER G21796-074
J 0
(-6625 1350);
DISPLAY 0.617021 (-6625 1350);
PAINT BLUE (-6625 1350);
FORCEPROP 1 LAST MATERIAL CHIP
J 0
(-6275 1425);
DISPLAY 0.617021 (-6275 1425);
PAINT SKYBLUE (-6275 1425);
FORCEPROP 1 LAST LOCATION R3U1
J 0
(-6475 1550);
DISPLAY 0.617021 (-6475 1550);
PAINT AQUA (-6475 1550);
FORCEPROP 1 LAST PACK_TYPE 0402
J 0
(-6100 1425);
DISPLAY 0.617021 (-6100 1425);
PAINT SKYBLUE (-6100 1425);
FORCEPROP 1 LASTPIN (-6525 1500) $PN 1
J 0
(-6513 1512);
DISPLAY 0.787234 (-6513 1512);
PAINT ORANGE (-6513 1512);
DISPLAY INVISIBLE (-6513 1512);
FORCEPROP 1 LASTPIN (-6325 1500) $PN 2
J 0
(-6363 1512);
DISPLAY 0.787234 (-6363 1512);
PAINT ORANGE (-6363 1512);
DISPLAY INVISIBLE (-6363 1512);
FORCEPROP 2 LAST CDS_LIB mstr_discrete
J 0
(-6425 1500);
PAINT ORANGE (-6425 1500);
DISPLAY INVISIBLE (-6425 1500);
FORCEPROP 2 LAST CDS_LOCATION R3U1
J 0
(-6475 1550);
DISPLAY 0.617021 (-6475 1550);
PAINT AQUA (-6475 1550);
DISPLAY INVISIBLE (-6475 1550);
FORCEPROP 2 LAST ROOM SB_SPI
J 0
(-6475 1600);
DISPLAY 1.021277 (-6475 1600);
PAINT ORANGE (-6475 1600);
DISPLAY INVISIBLE (-6475 1600);
FORCEPROP 2 LAST BOM_COST MIO_BIOS_MEM
J 0
(-6475 1650);
DISPLAY 1.021277 (-6475 1650);
PAINT ORANGE (-6475 1650);
DISPLAY INVISIBLE (-6475 1650);
FORCEPROP 1 LAST PATH I156
J 0
(-6475 1650);
DISPLAY 0.978723 (-6475 1650);
PAINT WHITE (-6475 1650);
DISPLAY INVISIBLE (-6475 1650);
FORCEPROP 2 LAST CDS_SEC 1
J 0
(-6475 1700);
PAINT MONO (-6475 1700);
DISPLAY INVISIBLE (-6475 1700);
FORCEPROP 2 LAST $SEC 1
J 0
(-6475 1700);
PAINT MONO (-6475 1700);
DISPLAY INVISIBLE (-6475 1700);
FORCEPROP 2 LAST NO_XNET_CONNECTION 1
J 0
(-6475 1700);
PAINT MONO (-6475 1700);
DISPLAY INVISIBLE (-6475 1700);
FORCEADD RES..1
(-6400 1225);
FORCEPROP 1 LAST WATTAGE 1/16W
J 2
(-6600 1150);
DISPLAY 0.617021 (-6600 1150);
PAINT SKYBLUE (-6600 1150);
FORCEPROP 1 LAST VALUE 33.2
J 2
(-6475 1150);
DISPLAY 0.617021 (-6475 1150);
PAINT SKYBLUE (-6475 1150);
FORCEPROP 1 LAST PART_NUMBER G21796-074
J 0
(-6600 1075);
DISPLAY 0.617021 (-6600 1075);
PAINT BLUE (-6600 1075);
FORCEPROP 1 LAST LOCATION R3T1
J 0
(-6450 1275);
DISPLAY 0.617021 (-6450 1275);
PAINT AQUA (-6450 1275);
FORCEPROP 1 LAST TOLERANCE 1%
J 0
(-6375 1150);
DISPLAY 0.617021 (-6375 1150);
PAINT SKYBLUE (-6375 1150);
FORCEPROP 1 LAST MATERIAL CHIP
J 0
(-6250 1150);
DISPLAY 0.617021 (-6250 1150);
PAINT SKYBLUE (-6250 1150);
FORCEPROP 1 LAST PACK_TYPE 0402
J 0
(-6075 1150);
DISPLAY 0.617021 (-6075 1150);
PAINT SKYBLUE (-6075 1150);
FORCEPROP 1 LASTPIN (-6500 1225) $PN 1
J 0
(-6488 1237);
DISPLAY 0.787234 (-6488 1237);
PAINT ORANGE (-6488 1237);
DISPLAY INVISIBLE (-6488 1237);
FORCEPROP 2 LAST CDS_LOCATION R3T1
J 0
(-6450 1275);
DISPLAY 0.617021 (-6450 1275);
PAINT AQUA (-6450 1275);
DISPLAY INVISIBLE (-6450 1275);
FORCEPROP 2 LAST CDS_SEC 1
J 0
(-6450 1425);
PAINT MONO (-6450 1425);
DISPLAY INVISIBLE (-6450 1425);
FORCEPROP 2 LAST $SEC 1
J 0
(-6450 1425);
PAINT MONO (-6450 1425);
DISPLAY INVISIBLE (-6450 1425);
FORCEPROP 2 LAST NO_XNET_CONNECTION 1
J 0
(-6450 1425);
PAINT MONO (-6450 1425);
DISPLAY INVISIBLE (-6450 1425);
FORCEPROP 2 LAST BOM_COST MIO_BIOS_MEM
J 0
(-6450 1375);
DISPLAY 1.021277 (-6450 1375);
PAINT ORANGE (-6450 1375);
DISPLAY INVISIBLE (-6450 1375);
FORCEPROP 2 LAST ROOM SB_SPI
J 0
(-6450 1325);
DISPLAY 1.021277 (-6450 1325);
PAINT ORANGE (-6450 1325);
DISPLAY INVISIBLE (-6450 1325);
FORCEPROP 1 LAST PATH I157
J 0
(-6450 1375);
DISPLAY 0.978723 (-6450 1375);
PAINT WHITE (-6450 1375);
DISPLAY INVISIBLE (-6450 1375);
FORCEPROP 2 LAST CDS_LIB mstr_discrete
J 0
(-6400 1225);
PAINT ORANGE (-6400 1225);
DISPLAY INVISIBLE (-6400 1225);
FORCEPROP 1 LASTPIN (-6300 1225) $PN 2
J 0
(-6338 1237);
DISPLAY 0.787234 (-6338 1237);
PAINT ORANGE (-6338 1237);
DISPLAY INVISIBLE (-6338 1237);
FORCEADD OFFPAGE..5
(-7075 1875);
FORCEPROP 2 LAST $XR0 153 
J 0
(-7330 1875);
DISPLAY 0.638298 (-7330 1875);
PAINT MONO (-7330 1875);
FORCEPROP 2 LAST $XR1 154 
J 0
(-7450 1875);
DISPLAY 0.638298 (-7450 1875);
PAINT MONO (-7450 1875);
FORCEPROP 2 LAST PATH I158
J 0
(-7350 1925);
DISPLAY 1.021277 (-7350 1925);
PAINT ORANGE (-7350 1925);
DISPLAY INVISIBLE (-7350 1925);
FORCEPROP 2 LAST CDS_LIB mstr_standard
J 1
(-7075 1875);
PAINT ORANGE (-7075 1875);
DISPLAY INVISIBLE (-7075 1875);
FORCEPROP 1 LAST COMMENT_BODY TRUE
J 0
(-6975 1800);
DISPLAY 1.170213 (-6975 1800);
PAINT GREEN (-6975 1800);
DISPLAY INVISIBLE (-6975 1800);
FORCEPROP 1 LAST OFFPAGE TRUE
J 0
(-6750 1750);
PAINT GREEN (-6750 1750);
DISPLAY INVISIBLE (-6750 1750);
FORCEADD OFFPAGE..1
(-7075 1925);
FORCEPROP 2 LAST $XR0 153 
J 0
(-7357 1925);
DISPLAY 0.638298 (-7357 1925);
PAINT MONO (-7357 1925);
FORCEPROP 2 LAST PATH I159
J 0
(-7325 1975);
DISPLAY 1.021277 (-7325 1975);
PAINT ORANGE (-7325 1975);
DISPLAY INVISIBLE (-7325 1975);
FORCEPROP 2 LAST CDS_LIB mstr_standard
J 0
(-7075 1925);
PAINT ORANGE (-7075 1925);
DISPLAY INVISIBLE (-7075 1925);
FORCEPROP 1 LAST COMMENT_BODY TRUE
J 0
(-6950 1825);
DISPLAY 0.872340 (-6950 1825);
PAINT GREEN (-6950 1825);
DISPLAY INVISIBLE (-6950 1825);
FORCEPROP 1 LAST OFFPAGE TRUE
J 0
(-6750 1800);
DISPLAY 0.872340 (-6750 1800);
PAINT GREEN (-6750 1800);
DISPLAY INVISIBLE (-6750 1800);
FORCEADD OFFPAGE..1
(-7075 1625);
FORCEPROP 2 LAST $XR0 154 
J 0
(-7357 1625);
DISPLAY 0.638298 (-7357 1625);
PAINT MONO (-7357 1625);
FORCEPROP 2 LAST PATH I161
J 0
(-7325 1675);
DISPLAY 1.021277 (-7325 1675);
PAINT ORANGE (-7325 1675);
DISPLAY INVISIBLE (-7325 1675);
FORCEPROP 1 LAST COMMENT_BODY TRUE
J 0
(-6950 1525);
DISPLAY 0.978723 (-6950 1525);
PAINT PEACH (-6950 1525);
DISPLAY INVISIBLE (-6950 1525);
FORCEPROP 1 LAST OFFPAGE TRUE
J 0
(-6750 1500);
PAINT GREEN (-6750 1500);
DISPLAY INVISIBLE (-6750 1500);
FORCEPROP 2 LAST CDS_LIB mstr_standard
J 0
(-7075 1625);
DISPLAY 1.531915 (-7075 1625);
PAINT ORANGE (-7075 1625);
DISPLAY INVISIBLE (-7075 1625);
FORCEADD OFFPAGE..1
(-7075 1725);
FORCEPROP 2 LAST $XR0 154 
J 0
(-7357 1725);
DISPLAY 0.638298 (-7357 1725);
PAINT MONO (-7357 1725);
FORCEPROP 2 LAST $XR1 153 
J 0
(-7477 1725);
DISPLAY 0.638298 (-7477 1725);
PAINT MONO (-7477 1725);
FORCEPROP 2 LAST PATH I162
J 0
(-7325 1775);
DISPLAY 1.021277 (-7325 1775);
PAINT ORANGE (-7325 1775);
DISPLAY INVISIBLE (-7325 1775);
FORCEPROP 2 LAST CDS_LIB mstr_standard
J 0
(-7075 1725);
DISPLAY 1.531915 (-7075 1725);
PAINT ORANGE (-7075 1725);
DISPLAY INVISIBLE (-7075 1725);
FORCEPROP 1 LAST COMMENT_BODY TRUE
J 0
(-6950 1625);
DISPLAY 0.978723 (-6950 1625);
PAINT PEACH (-6950 1625);
DISPLAY INVISIBLE (-6950 1625);
FORCEPROP 1 LAST OFFPAGE TRUE
J 0
(-6750 1600);
PAINT GREEN (-6750 1600);
DISPLAY INVISIBLE (-6750 1600);
FORCEADD OFFPAGE..1
(-7300 1500);
FORCEPROP 2 LAST $XR0 154 
J 0
(-7552 1500);
DISPLAY 0.638298 (-7552 1500);
PAINT MONO (-7552 1500);
FORCEPROP 2 LAST $XR1 153 
J 0
(-7672 1500);
DISPLAY 0.638298 (-7672 1500);
PAINT MONO (-7672 1500);
FORCEPROP 1 LAST COMMENT_BODY TRUE
J 0
(-7175 1400);
DISPLAY 0.872340 (-7175 1400);
PAINT GREEN (-7175 1400);
DISPLAY INVISIBLE (-7175 1400);
FORCEPROP 2 LAST CDS_LIB mstr_standard
J 0
(-7300 1500);
PAINT ORANGE (-7300 1500);
DISPLAY INVISIBLE (-7300 1500);
FORCEPROP 2 LAST PATH I163
J 0
(-7550 1550);
DISPLAY 1.021277 (-7550 1550);
PAINT ORANGE (-7550 1550);
DISPLAY INVISIBLE (-7550 1550);
FORCEPROP 1 LAST OFFPAGE TRUE
J 0
(-6975 1375);
DISPLAY 0.872340 (-6975 1375);
PAINT GREEN (-6975 1375);
DISPLAY INVISIBLE (-6975 1375);
FORCEADD OFFPAGE..1
(-7300 1225);
FORCEPROP 2 LAST $XR0 154 
J 0
(-7552 1225);
DISPLAY 0.638298 (-7552 1225);
PAINT MONO (-7552 1225);
FORCEPROP 2 LAST $XR1 153 
J 0
(-7672 1225);
DISPLAY 0.638298 (-7672 1225);
PAINT MONO (-7672 1225);
FORCEPROP 2 LAST PATH I164
J 0
(-7550 1275);
DISPLAY 1.021277 (-7550 1275);
PAINT ORANGE (-7550 1275);
DISPLAY INVISIBLE (-7550 1275);
FORCEPROP 1 LAST COMMENT_BODY TRUE
J 0
(-7175 1125);
DISPLAY 0.872340 (-7175 1125);
PAINT GREEN (-7175 1125);
DISPLAY INVISIBLE (-7175 1125);
FORCEPROP 2 LAST CDS_LIB mstr_standard
J 0
(-7300 1225);
PAINT ORANGE (-7300 1225);
DISPLAY INVISIBLE (-7300 1225);
FORCEPROP 1 LAST OFFPAGE TRUE
J 0
(-6975 1100);
DISPLAY 0.872340 (-6975 1100);
PAINT GREEN (-6975 1100);
DISPLAY INVISIBLE (-6975 1100);
FORCEADD W25Q256..1
(-4825 1875);
FORCEPROP 2 LASTPIN (-5375 1725) $PN 16
J 2
(-5385 1735);
DISPLAY 0.617021 (-5385 1735);
PAINT ORANGE (-5385 1735);
FORCEPROP 2 LASTPIN (-5375 1625) $PN 7
J 2
(-5385 1635);
DISPLAY 0.617021 (-5385 1635);
PAINT ORANGE (-5385 1635);
FORCEPROP 2 LASTPIN (-5375 1825) $PN 15
J 2
(-5385 1835);
DISPLAY 0.617021 (-5385 1835);
PAINT ORANGE (-5385 1835);
FORCEPROP 2 LASTPIN (-5375 1875) $PN 8
J 2
(-5385 1885);
DISPLAY 0.617021 (-5385 1885);
PAINT ORANGE (-5385 1885);
FORCEPROP 2 LASTPIN (-5375 1975) $PN 1
J 2
(-5385 1985);
DISPLAY 0.617021 (-5385 1985);
PAINT ORANGE (-5385 1985);
FORCEPROP 2 LASTPIN (-5375 1575) $PN 3
J 2
(-5385 1585);
DISPLAY 0.617021 (-5385 1585);
PAINT ORANGE (-5385 1585);
FORCEPROP 2 LASTPIN (-5375 1925) $PN 9
J 2
(-5385 1935);
DISPLAY 0.617021 (-5385 1935);
PAINT ORANGE (-5385 1935);
FORCEPROP 1 LAST PART_NUMBER H25002-001
J 0
(-5325 1375);
DISPLAY 0.617021 (-5325 1375);
PAINT BLUE (-5325 1375);
FORCEPROP 2 LASTPIN (-4275 1625) $PN 10
J 0
(-4265 1635);
DISPLAY 0.617021 (-4265 1635);
PAINT ORANGE (-4265 1635);
FORCEPROP 2 LASTPIN (-4275 1775) $PN 14
J 0
(-4265 1785);
DISPLAY 0.617021 (-4265 1785);
PAINT ORANGE (-4265 1785);
FORCEPROP 2 LASTPIN (-4275 1975) $PN 6
J 0
(-4265 1985);
DISPLAY 0.617021 (-4265 1985);
PAINT ORANGE (-4265 1985);
FORCEPROP 2 LASTPIN (-4275 1825) $PN 13
J 0
(-4265 1835);
DISPLAY 0.617021 (-4265 1835);
PAINT ORANGE (-4265 1835);
FORCEPROP 2 LASTPIN (-4275 1875) $PN 12
J 0
(-4265 1885);
DISPLAY 0.617021 (-4265 1885);
PAINT ORANGE (-4265 1885);
FORCEPROP 2 LASTPIN (-4275 1925) $PN 11
J 0
(-4265 1935);
DISPLAY 0.617021 (-4265 1935);
PAINT ORANGE (-4265 1935);
FORCEPROP 2 LASTPIN (-4275 2025) $PN 5
J 0
(-4265 2035);
DISPLAY 0.617021 (-4265 2035);
PAINT ORANGE (-4265 2035);
FORCEPROP 2 LASTPIN (-5375 2075) $PN 2
J 2
(-5385 2085);
DISPLAY 0.617021 (-5385 2085);
PAINT ORANGE (-5385 2085);
FORCEPROP 1 LAST MATERIAL IC
J 0
(-5325 2275);
DISPLAY 0.617021 (-5325 2275);
PAINT SKYBLUE (-5325 2275);
FORCEPROP 1 LAST LOCATION U3T1
J 0
(-5225 2275);
DISPLAY 0.617021 (-5225 2275);
PAINT AQUA (-5225 2275);
FORCEPROP 2 LASTPIN (-4275 2075) $PN 4
J 0
(-4265 2085);
DISPLAY 0.617021 (-4265 2085);
PAINT ORANGE (-4265 2085);
FORCEPROP 2 LAST CDS_LIB mstr_memory
J 0
(-4825 1875);
PAINT MONO (-4825 1875);
DISPLAY INVISIBLE (-4825 1875);
FORCEPROP 2 LAST ROOM SB_SPI
J 0
(-5325 2325);
DISPLAY 1.021277 (-5325 2325);
PAINT ORANGE (-5325 2325);
DISPLAY INVISIBLE (-5325 2325);
FORCEPROP 2 LAST CDS_LOCATION U3T1
J 0
(-5225 2275);
DISPLAY 0.617021 (-5225 2275);
PAINT AQUA (-5225 2275);
DISPLAY INVISIBLE (-5225 2275);
FORCEPROP 2 LAST BOM_COST MIO_BIOS_MEM
J 0
(-5325 2375);
DISPLAY 1.021277 (-5325 2375);
PAINT ORANGE (-5325 2375);
DISPLAY INVISIBLE (-5325 2375);
FORCEPROP 1 LAST PACK_TYPE XSOI
J 0
(-5325 2375);
PAINT SKYBLUE (-5325 2375);
DISPLAY INVISIBLE (-5325 2375);
FORCEPROP 2 LAST SEC_TYPE XSOI
J 0
(-4825 2325);
DISPLAY 1.021277 (-4825 2325);
PAINT ORANGE (-4825 2325);
DISPLAY INVISIBLE (-4825 2325);
FORCEPROP 2 LAST SEC 1
J 0
(-4825 2325);
DISPLAY 0.680851 (-4825 2325);
PAINT MONO (-4825 2325);
DISPLAY INVISIBLE (-4825 2325);
FORCEPROP 1 LAST PATH I165
J 0
(-4825 2275);
PAINT GREEN (-4825 2275);
DISPLAY INVISIBLE (-4825 2275);
FORCEADD RES..1
(-6550 3825);
FORCEPROP 1 LAST WATTAGE 1/16W
J 2
(-6675 3775);
DISPLAY 0.617021 (-6675 3775);
PAINT SKYBLUE (-6675 3775);
FORCEPROP 1 LAST VALUE 33.2
J 2
(-6575 3775);
DISPLAY 0.617021 (-6575 3775);
PAINT SKYBLUE (-6575 3775);
FORCEPROP 1 LAST TOLERANCE 1%
J 0
(-6475 3775);
DISPLAY 0.617021 (-6475 3775);
PAINT SKYBLUE (-6475 3775);
FORCEPROP 1 LASTPIN (-6650 3825) $PN 1
J 0
(-6638 3837);
DISPLAY 0.617021 (-6638 3837);
PAINT MONO (-6638 3837);
FORCEPROP 1 LASTPIN (-6450 3825) $PN 2
J 0
(-6488 3837);
DISPLAY 0.617021 (-6488 3837);
PAINT MONO (-6488 3837);
FORCEPROP 1 LAST LOCATION R8F8
J 0
(-6600 3850);
DISPLAY 0.617021 (-6600 3850);
PAINT AQUA (-6600 3850);
FORCEPROP 1 LAST MATERIAL CHIP
J 0
(-6400 3775);
DISPLAY 0.617021 (-6400 3775);
PAINT SKYBLUE (-6400 3775);
FORCEPROP 1 LAST PACK_TYPE 0402
J 0
(-6475 3725);
DISPLAY 0.617021 (-6475 3725);
PAINT SKYBLUE (-6475 3725);
FORCEPROP 1 LAST PART_NUMBER G21796-074
J 0
(-6425 3825);
DISPLAY 0.617021 (-6425 3825);
PAINT BLUE (-6425 3825);
FORCEPROP 2 LAST CDS_LIB mstr_discrete
J 0
(-6550 3825);
PAINT ORANGE (-6550 3825);
DISPLAY INVISIBLE (-6550 3825);
FORCEPROP 2 LAST ROOM MIO_BIOS_MEM
J 0
(-6600 3965);
DISPLAY 0.787234 (-6600 3965);
PAINT SKYBLUE (-6600 3965);
DISPLAY INVISIBLE (-6600 3965);
FORCEPROP 1 LAST PATH I166
J 0
(-6600 3975);
DISPLAY 0.978723 (-6600 3975);
PAINT WHITE (-6600 3975);
DISPLAY INVISIBLE (-6600 3975);
FORCEPROP 2 LAST CDS_LOCATION R8F8
J 0
(-6600 3850);
DISPLAY 0.617021 (-6600 3850);
PAINT AQUA (-6600 3850);
DISPLAY INVISIBLE (-6600 3850);
FORCEPROP 2 LAST $SEC 1
J 0
(-6600 4025);
DISPLAY 0.936170 (-6600 4025);
PAINT MONO (-6600 4025);
DISPLAY INVISIBLE (-6600 4025);
FORCEPROP 2 LAST CDS_SEC 1
J 0
(-6600 4025);
DISPLAY 1.404255 (-6600 4025);
PAINT ORANGE (-6600 4025);
DISPLAY INVISIBLE (-6600 4025);
FORCEADD RES..1
(-6525 1725);
FORCEPROP 1 LAST WATTAGE 1/16W
J 2
(-6650 1675);
DISPLAY 0.617021 (-6650 1675);
PAINT SKYBLUE (-6650 1675);
FORCEPROP 1 LAST VALUE 33.2
J 2
(-6550 1675);
DISPLAY 0.617021 (-6550 1675);
PAINT SKYBLUE (-6550 1675);
FORCEPROP 1 LAST LOCATION R8F7
J 0
(-6575 1750);
DISPLAY 0.617021 (-6575 1750);
PAINT AQUA (-6575 1750);
FORCEPROP 1 LAST PACK_TYPE 0402
J 0
(-6450 1625);
DISPLAY 0.617021 (-6450 1625);
PAINT SKYBLUE (-6450 1625);
FORCEPROP 1 LAST TOLERANCE 1%
J 0
(-6450 1675);
DISPLAY 0.617021 (-6450 1675);
PAINT SKYBLUE (-6450 1675);
FORCEPROP 1 LAST MATERIAL CHIP
J 0
(-6375 1675);
DISPLAY 0.617021 (-6375 1675);
PAINT SKYBLUE (-6375 1675);
FORCEPROP 1 LAST PART_NUMBER G21796-074
J 0
(-6400 1725);
DISPLAY 0.617021 (-6400 1725);
PAINT BLUE (-6400 1725);
FORCEPROP 1 LASTPIN (-6625 1725) $PN 1
J 0
(-6613 1737);
DISPLAY 0.787234 (-6613 1737);
PAINT ORANGE (-6613 1737);
DISPLAY INVISIBLE (-6613 1737);
FORCEPROP 2 LAST CDS_LOCATION R8F7
J 0
(-6575 1750);
DISPLAY 0.617021 (-6575 1750);
PAINT AQUA (-6575 1750);
DISPLAY INVISIBLE (-6575 1750);
FORCEPROP 2 LAST CDS_LIB mstr_discrete
J 0
(-6525 1725);
PAINT ORANGE (-6525 1725);
DISPLAY INVISIBLE (-6525 1725);
FORCEPROP 1 LASTPIN (-6425 1725) $PN 2
J 0
(-6463 1737);
DISPLAY 0.787234 (-6463 1737);
PAINT ORANGE (-6463 1737);
DISPLAY INVISIBLE (-6463 1737);
FORCEPROP 2 LAST ROOM MIO_BIOS_MEM
J 0
(-6575 1865);
DISPLAY 0.787234 (-6575 1865);
PAINT SKYBLUE (-6575 1865);
DISPLAY INVISIBLE (-6575 1865);
FORCEPROP 1 LAST PATH I167
J 0
(-6575 1875);
DISPLAY 0.978723 (-6575 1875);
PAINT WHITE (-6575 1875);
DISPLAY INVISIBLE (-6575 1875);
FORCEPROP 2 LAST CDS_SEC 1
J 0
(-6575 1925);
DISPLAY 1.021277 (-6575 1925);
PAINT ORANGE (-6575 1925);
DISPLAY INVISIBLE (-6575 1925);
FORCEPROP 2 LAST $SEC 1
J 0
(-6575 1925);
DISPLAY 0.680851 (-6575 1925);
PAINT MONO (-6575 1925);
DISPLAY INVISIBLE (-6575 1925);
FORCEADD RES..2
(-1750 3925);
FORCEPROP 1 LAST PACK_TYPE 0402
J 0
(-1710 3750);
DISPLAY 0.617021 (-1710 3750);
PAINT SKYBLUE (-1710 3750);
FORCEPROP 1 LASTPIN (-1750 3825) $PN 2
J 0
(-1745 3835);
DISPLAY 0.617021 (-1745 3835);
PAINT ORANGE (-1745 3835);
FORCEPROP 1 LASTPIN (-1750 4025) $PN 1
J 0
(-1745 3987);
DISPLAY 0.617021 (-1745 3987);
PAINT ORANGE (-1745 3987);
FORCEPROP 1 LAST WATTAGE 1/16W
J 0
(-1710 3900);
DISPLAY 0.617021 (-1710 3900);
PAINT SKYBLUE (-1710 3900);
FORCEPROP 1 LAST LOCATION R7F28
J 0
(-1705 4050);
DISPLAY 0.617021 (-1705 4050);
PAINT AQUA (-1705 4050);
FORCEPROP 1 LAST VALUE 10.0K
J 0
(-1705 4000);
DISPLAY 0.617021 (-1705 4000);
PAINT SKYBLUE (-1705 4000);
FORCEPROP 1 LAST TOLERANCE 1%
J 0
(-1705 3950);
DISPLAY 0.617021 (-1705 3950);
PAINT SKYBLUE (-1705 3950);
FORCEPROP 1 LAST MATERIAL CHIP
J 0
(-1710 3850);
DISPLAY 0.617021 (-1710 3850);
PAINT SKYBLUE (-1710 3850);
FORCEPROP 1 LAST PART_NUMBER G21796-016
J 0
(-1710 3800);
DISPLAY 0.617021 (-1710 3800);
PAINT BLUE (-1710 3800);
FORCEPROP 2 LAST CDS_LIB mstr_discrete
J 0
(-1750 3925);
PAINT MONO (-1750 3925);
DISPLAY INVISIBLE (-1750 3925);
FORCEPROP 2 LAST CDS_LOCATION R7F28
J 0
(-1705 4050);
DISPLAY 0.617021 (-1705 4050);
PAINT AQUA (-1705 4050);
DISPLAY INVISIBLE (-1705 4050);
FORCEPROP 0 LAST BOM_COST MIO_BIOS_MEM
J 0
(-1700 4250);
DISPLAY 1.021277 (-1700 4250);
PAINT ORANGE (-1700 4250);
DISPLAY INVISIBLE (-1700 4250);
FORCEPROP 2 LAST SEC_TYPE 0402
J 0
(-1700 4150);
DISPLAY 1.021277 (-1700 4150);
PAINT ORANGE (-1700 4150);
DISPLAY INVISIBLE (-1700 4150);
FORCEPROP 0 LAST ROOM SB_SPI
J 0
(-1700 4150);
DISPLAY 1.021277 (-1700 4150);
PAINT ORANGE (-1700 4150);
DISPLAY INVISIBLE (-1700 4150);
FORCEPROP 1 LAST PATH I168
J 0
(-1700 4100);
DISPLAY 0.978723 (-1700 4100);
PAINT WHITE (-1700 4100);
DISPLAY INVISIBLE (-1700 4100);
FORCEPROP 2 LAST NO_XNET_CONNECTION 1
J 0
(-1700 4150);
PAINT MONO (-1700 4150);
DISPLAY INVISIBLE (-1700 4150);
FORCEPROP 2 LAST SEC 1
J 0
(-1700 4150);
DISPLAY 0.680851 (-1700 4150);
PAINT MONO (-1700 4150);
DISPLAY INVISIBLE (-1700 4150);
FORCEADD P3V3_STBY..1
(-1750 4175);
FORCEPROP 3 LASTPIN (-1750 4125) SIG_NAME P3V3_STBY\g
J 0
(-1740 4135);
DISPLAY 0.659574 (-1740 4135);
PAINT MONO (-1740 4135);
DISPLAY INVISIBLE (-1740 4135);
FORCEPROP 1 LAST HDL_POWER P3V3_STBY
J 0
(-2050 4050);
DISPLAY 0.872340 (-2050 4050);
PAINT ORANGE (-2050 4050);
DISPLAY INVISIBLE (-2050 4050);
FORCEPROP 1 LAST BODY_TYPE PLUMBING
J 0
(-1795 4132);
DISPLAY 0.340426 (-1795 4132);
PAINT GREEN (-1795 4132);
DISPLAY INVISIBLE (-1795 4132);
FORCEPROP 1 LAST VOLTAGE 3.3V
J 0
(-1795 4132);
DISPLAY 0.340426 (-1795 4132);
PAINT SKYBLUE (-1795 4132);
DISPLAY INVISIBLE (-1795 4132);
FORCEPROP 1 LAST SIZE 1B
J 0
(-1705 4197);
DISPLAY 0.340426 (-1705 4197);
PAINT GREEN (-1705 4197);
DISPLAY INVISIBLE (-1705 4197);
FORCEPROP 2 LAST CDS_LIB mstr_symbols
J 0
(-1750 4175);
PAINT MONO (-1750 4175);
DISPLAY INVISIBLE (-1750 4175);
FORCEPROP 1 LAST PATH I169
J 0
(-1705 4177);
DISPLAY 0.340426 (-1705 4177);
PAINT GREEN (-1705 4177);
DISPLAY INVISIBLE (-1705 4177);
FORCEADD RES..2
(-1750 3550);
FORCEPROP 1 LASTPIN (-1750 3450) $PN 2
J 0
(-1745 3460);
DISPLAY 0.617021 (-1745 3460);
PAINT ORANGE (-1745 3460);
FORCEPROP 1 LAST WATTAGE 1/16W
J 0
(-1710 3525);
DISPLAY 0.617021 (-1710 3525);
PAINT SKYBLUE (-1710 3525);
FORCEPROP 1 LAST PACK_TYPE 0402
J 0
(-1710 3375);
DISPLAY 0.617021 (-1710 3375);
PAINT SKYBLUE (-1710 3375);
FORCEPROP 1 LAST MATERIAL EMPTY
J 0
(-1710 3475);
DISPLAY 0.617021 (-1710 3475);
PAINT RED (-1710 3475);
FORCEPROP 1 LAST TOLERANCE 1%
J 0
(-1705 3575);
DISPLAY 0.617021 (-1705 3575);
PAINT SKYBLUE (-1705 3575);
FORCEPROP 1 LASTPIN (-1750 3650) $PN 1
J 0
(-1745 3612);
DISPLAY 0.617021 (-1745 3612);
PAINT ORANGE (-1745 3612);
FORCEPROP 1 LAST VALUE 10.0K
J 0
(-1705 3625);
DISPLAY 0.617021 (-1705 3625);
PAINT SKYBLUE (-1705 3625);
FORCEPROP 1 LAST LOCATION R7F30
J 0
(-1705 3675);
DISPLAY 0.617021 (-1705 3675);
PAINT AQUA (-1705 3675);
FORCEPROP 1 LAST PART_NUMBER G21796-016
J 0
(-1710 3425);
DISPLAY 0.617021 (-1710 3425);
PAINT BLUE (-1710 3425);
FORCEPROP 2 LAST CDS_LIB mstr_discrete
J 0
(-1750 3550);
PAINT MONO (-1750 3550);
DISPLAY INVISIBLE (-1750 3550);
FORCEPROP 2 LAST CDS_LOCATION R7F30
J 0
(-1705 3675);
DISPLAY 0.617021 (-1705 3675);
PAINT AQUA (-1705 3675);
DISPLAY INVISIBLE (-1705 3675);
FORCEPROP 0 LAST ROOM SB_SPI
J 0
(-1700 3775);
DISPLAY 1.021277 (-1700 3775);
PAINT ORANGE (-1700 3775);
DISPLAY INVISIBLE (-1700 3775);
FORCEPROP 1 LAST PATH I170
J 0
(-1700 3725);
DISPLAY 0.978723 (-1700 3725);
PAINT WHITE (-1700 3725);
DISPLAY INVISIBLE (-1700 3725);
FORCEPROP 2 LAST SEC 1
J 0
(-1700 3775);
DISPLAY 0.680851 (-1700 3775);
PAINT MONO (-1700 3775);
DISPLAY INVISIBLE (-1700 3775);
FORCEPROP 2 LAST SEC_TYPE 0402
J 0
(-1700 3775);
DISPLAY 1.021277 (-1700 3775);
PAINT ORANGE (-1700 3775);
DISPLAY INVISIBLE (-1700 3775);
FORCEPROP 0 LAST BOM_COST MIO_BIOS_MEM
J 0
(-1700 3875);
DISPLAY 1.021277 (-1700 3875);
PAINT ORANGE (-1700 3875);
DISPLAY INVISIBLE (-1700 3875);
FORCEADD OFFPAGE..2
(-650 3750);
FORCEPROP 2 LAST $XR0 153 
J 0
(-461 3750);
DISPLAY 0.638298 (-461 3750);
PAINT MONO (-461 3750);
FORCEPROP 1 LAST COMMENT_BODY TRUE
J 0
(-695 3655);
DISPLAY 0.872340 (-695 3655);
PAINT GREEN (-695 3655);
DISPLAY INVISIBLE (-695 3655);
FORCEPROP 2 LAST CDS_LIB mstr_standard
J 0
(-650 3750);
PAINT MONO (-650 3750);
DISPLAY INVISIBLE (-650 3750);
FORCEPROP 2 LAST PATH I171
J 0
(-475 3825);
DISPLAY 1.021277 (-475 3825);
PAINT ORANGE (-475 3825);
DISPLAY INVISIBLE (-475 3825);
FORCEPROP 1 LAST OFFPAGE TRUE
J 0
(-325 3625);
DISPLAY 0.872340 (-325 3625);
PAINT GREEN (-325 3625);
DISPLAY INVISIBLE (-325 3625);
FORCEADD GND..1
(-1750 3325);
FORCEPROP 3 LASTPIN (-1750 3375) SIG_NAME GND\g
J 0
(-1740 3385);
DISPLAY 0.659574 (-1740 3385);
PAINT MONO (-1740 3385);
DISPLAY INVISIBLE (-1740 3385);
FORCEPROP 1 LAST BODY_TYPE PLUMBING
J 0
(-1795 3282);
DISPLAY 0.340426 (-1795 3282);
PAINT GREEN (-1795 3282);
DISPLAY INVISIBLE (-1795 3282);
FORCEPROP 1 LAST VOLTAGE 0.0V
J 0
(-1795 3282);
DISPLAY 0.340426 (-1795 3282);
PAINT SKYBLUE (-1795 3282);
DISPLAY INVISIBLE (-1795 3282);
FORCEPROP 1 LAST SIZE 1B
J 0
(-1675 3275);
DISPLAY 0.872340 (-1675 3275);
PAINT AQUA (-1675 3275);
DISPLAY INVISIBLE (-1675 3275);
FORCEPROP 1 LAST PATH I172
J 0
(-1675 3325);
DISPLAY 0.872340 (-1675 3325);
PAINT AQUA (-1675 3325);
DISPLAY INVISIBLE (-1675 3325);
FORCEPROP 2 LAST CDS_LIB mstr_symbols
J 0
(-1750 3325);
PAINT MONO (-1750 3325);
DISPLAY INVISIBLE (-1750 3325);
FORCEPROP 1 LAST HDL_POWER GND
J 0
(-1750 3475);
DISPLAY 0.872340 (-1750 3475);
PAINT GREEN (-1750 3475);
DISPLAY INVISIBLE (-1750 3475);
FORCEADD OFFPAGE..2
(-675 2325);
FORCEPROP 2 LAST $XR0 153 
J 0
(-486 2325);
DISPLAY 0.638298 (-486 2325);
PAINT MONO (-486 2325);
FORCEPROP 1 LAST COMMENT_BODY TRUE
J 0
(-720 2230);
DISPLAY 0.872340 (-720 2230);
PAINT GREEN (-720 2230);
DISPLAY INVISIBLE (-720 2230);
FORCEPROP 2 LAST CDS_LIB mstr_standard
J 0
(-675 2325);
PAINT ORANGE (-675 2325);
DISPLAY INVISIBLE (-675 2325);
FORCEPROP 2 LAST PATH I173
J 0
(-475 2375);
DISPLAY 1.021277 (-475 2375);
PAINT ORANGE (-475 2375);
DISPLAY INVISIBLE (-475 2375);
FORCEPROP 1 LAST OFFPAGE TRUE
J 0
(-350 2200);
DISPLAY 0.872340 (-350 2200);
PAINT GREEN (-350 2200);
DISPLAY INVISIBLE (-350 2200);
FORCEADD RES..1
(-1450 2325);
FORCEPROP 1 LAST TOLERANCE 1%
J 0
(-1650 2275);
DISPLAY 0.617021 (-1650 2275);
PAINT SKYBLUE (-1650 2275);
FORCEPROP 1 LASTPIN (-1550 2325) $PN 1
J 0
(-1538 2337);
DISPLAY 0.617021 (-1538 2337);
PAINT ORANGE (-1538 2337);
FORCEPROP 1 LAST VALUE 10.0K
J 2
(-1475 2275);
DISPLAY 0.617021 (-1475 2275);
PAINT SKYBLUE (-1475 2275);
FORCEPROP 1 LAST PART_NUMBER G21796-016
J 0
(-1550 2225);
DISPLAY 0.617021 (-1550 2225);
PAINT BLUE (-1550 2225);
FORCEPROP 1 LAST WATTAGE 1/16W
J 2
(-1300 2275);
DISPLAY 0.617021 (-1300 2275);
PAINT SKYBLUE (-1300 2275);
FORCEPROP 1 LAST LOCATION R3T4
J 0
(-1475 2375);
DISPLAY 0.617021 (-1475 2375);
PAINT AQUA (-1475 2375);
FORCEPROP 1 LASTPIN (-1350 2325) $PN 2
J 0
(-1388 2337);
DISPLAY 0.617021 (-1388 2337);
PAINT ORANGE (-1388 2337);
FORCEPROP 1 LAST PACK_TYPE 0402
J 0
(-1150 2275);
DISPLAY 0.617021 (-1150 2275);
PAINT SKYBLUE (-1150 2275);
FORCEPROP 1 LAST MATERIAL CHIP
J 0
(-1275 2275);
DISPLAY 0.617021 (-1275 2275);
PAINT SKYBLUE (-1275 2275);
FORCEPROP 2 LAST ROOM SB_SPI
J 0
(-1475 2425);
DISPLAY 1.021277 (-1475 2425);
PAINT ORANGE (-1475 2425);
DISPLAY INVISIBLE (-1475 2425);
FORCEPROP 1 LAST PATH I174
J 0
(-1500 2475);
DISPLAY 0.978723 (-1500 2475);
PAINT WHITE (-1500 2475);
DISPLAY INVISIBLE (-1500 2475);
FORCEPROP 2 LAST CDS_LOCATION R3T4
J 0
(-1475 2375);
DISPLAY 0.617021 (-1475 2375);
PAINT AQUA (-1475 2375);
DISPLAY INVISIBLE (-1475 2375);
FORCEPROP 2 LAST CDS_LIB mstr_discrete
J 0
(-1450 2325);
PAINT ORANGE (-1450 2325);
DISPLAY INVISIBLE (-1450 2325);
FORCEPROP 2 LAST BOM_COST MIO_BIOS_MEM
J 0
(-1475 2475);
DISPLAY 1.021277 (-1475 2475);
PAINT ORANGE (-1475 2475);
DISPLAY INVISIBLE (-1475 2475);
FORCEPROP 2 LAST SEC_TYPE 0402
J 0
(-1500 2525);
DISPLAY 1.021277 (-1500 2525);
PAINT ORANGE (-1500 2525);
DISPLAY INVISIBLE (-1500 2525);
FORCEPROP 2 LAST SEC 1
J 0
(-1500 2525);
PAINT MONO (-1500 2525);
DISPLAY INVISIBLE (-1500 2525);
FORCEADD P3V3_STBY..1
(-1750 2525);
FORCEPROP 3 LASTPIN (-1750 2475) SIG_NAME P3V3_STBY\g
J 0
(-1740 2485);
DISPLAY 0.659574 (-1740 2485);
PAINT MONO (-1740 2485);
DISPLAY INVISIBLE (-1740 2485);
FORCEPROP 1 LAST HDL_POWER P3V3_STBY
J 0
(-2050 2400);
DISPLAY 0.872340 (-2050 2400);
PAINT ORANGE (-2050 2400);
DISPLAY INVISIBLE (-2050 2400);
FORCEPROP 1 LAST BODY_TYPE PLUMBING
J 0
(-1795 2482);
DISPLAY 0.340426 (-1795 2482);
PAINT GREEN (-1795 2482);
DISPLAY INVISIBLE (-1795 2482);
FORCEPROP 1 LAST VOLTAGE 3.3V
J 0
(-1795 2482);
DISPLAY 0.340426 (-1795 2482);
PAINT SKYBLUE (-1795 2482);
DISPLAY INVISIBLE (-1795 2482);
FORCEPROP 1 LAST PATH I175
J 0
(-1705 2527);
DISPLAY 0.340426 (-1705 2527);
PAINT GREEN (-1705 2527);
DISPLAY INVISIBLE (-1705 2527);
FORCEPROP 2 LAST CDS_LIB mstr_symbols
J 0
(-1750 2525);
PAINT ORANGE (-1750 2525);
DISPLAY INVISIBLE (-1750 2525);
FORCEPROP 1 LAST SIZE 1B
J 0
(-1705 2547);
DISPLAY 0.340426 (-1705 2547);
PAINT GREEN (-1705 2547);
DISPLAY INVISIBLE (-1705 2547);
FORCEADD P3V3_STBY..1
(-1750 2075);
FORCEPROP 3 LASTPIN (-1750 2025) SIG_NAME P3V3_STBY\g
J 0
(-1740 2035);
DISPLAY 0.659574 (-1740 2035);
PAINT MONO (-1740 2035);
DISPLAY INVISIBLE (-1740 2035);
FORCEPROP 1 LAST HDL_POWER P3V3_STBY
J 0
(-2050 1950);
DISPLAY 0.872340 (-2050 1950);
PAINT ORANGE (-2050 1950);
DISPLAY INVISIBLE (-2050 1950);
FORCEPROP 1 LAST BODY_TYPE PLUMBING
J 0
(-1795 2032);
DISPLAY 0.340426 (-1795 2032);
PAINT GREEN (-1795 2032);
DISPLAY INVISIBLE (-1795 2032);
FORCEPROP 1 LAST VOLTAGE 3.3V
J 0
(-1795 2032);
DISPLAY 0.340426 (-1795 2032);
PAINT SKYBLUE (-1795 2032);
DISPLAY INVISIBLE (-1795 2032);
FORCEPROP 1 LAST PATH I176
J 0
(-1705 2077);
DISPLAY 0.340426 (-1705 2077);
PAINT GREEN (-1705 2077);
DISPLAY INVISIBLE (-1705 2077);
FORCEPROP 1 LAST SIZE 1B
J 0
(-1705 2097);
DISPLAY 0.340426 (-1705 2097);
PAINT GREEN (-1705 2097);
DISPLAY INVISIBLE (-1705 2097);
FORCEPROP 2 LAST CDS_LIB mstr_symbols
J 0
(-1750 2075);
PAINT MONO (-1750 2075);
DISPLAY INVISIBLE (-1750 2075);
FORCEADD OFFPAGE..2
(-650 1650);
FORCEPROP 2 LAST $XR0 153 
J 0
(-461 1650);
DISPLAY 0.638298 (-461 1650);
PAINT MONO (-461 1650);
FORCEPROP 1 LAST COMMENT_BODY TRUE
J 0
(-695 1555);
DISPLAY 0.872340 (-695 1555);
PAINT GREEN (-695 1555);
DISPLAY INVISIBLE (-695 1555);
FORCEPROP 2 LAST CDS_LIB mstr_standard
J 0
(-650 1650);
PAINT MONO (-650 1650);
DISPLAY INVISIBLE (-650 1650);
FORCEPROP 2 LAST PATH I177
J 0
(-475 1725);
DISPLAY 1.021277 (-475 1725);
PAINT ORANGE (-475 1725);
DISPLAY INVISIBLE (-475 1725);
FORCEPROP 1 LAST OFFPAGE TRUE
J 0
(-325 1525);
DISPLAY 0.872340 (-325 1525);
PAINT GREEN (-325 1525);
DISPLAY INVISIBLE (-325 1525);
FORCEADD RES..2
(-1750 1825);
FORCEPROP 1 LASTPIN (-1750 1725) $PN 2
J 0
(-1745 1735);
DISPLAY 0.617021 (-1745 1735);
PAINT ORANGE (-1745 1735);
FORCEPROP 1 LAST PACK_TYPE 0402
J 0
(-1710 1650);
DISPLAY 0.617021 (-1710 1650);
PAINT SKYBLUE (-1710 1650);
FORCEPROP 1 LAST MATERIAL CHIP
J 0
(-1710 1750);
DISPLAY 0.617021 (-1710 1750);
PAINT SKYBLUE (-1710 1750);
FORCEPROP 1 LASTPIN (-1750 1925) $PN 1
J 0
(-1745 1887);
DISPLAY 0.617021 (-1745 1887);
PAINT ORANGE (-1745 1887);
FORCEPROP 1 LAST LOCATION R3T12
J 0
(-1705 1950);
DISPLAY 0.617021 (-1705 1950);
PAINT AQUA (-1705 1950);
FORCEPROP 1 LAST VALUE 10.0K
J 0
(-1705 1900);
DISPLAY 0.617021 (-1705 1900);
PAINT SKYBLUE (-1705 1900);
FORCEPROP 1 LAST TOLERANCE 1%
J 0
(-1705 1850);
DISPLAY 0.617021 (-1705 1850);
PAINT SKYBLUE (-1705 1850);
FORCEPROP 1 LAST WATTAGE 1/16W
J 0
(-1710 1800);
DISPLAY 0.617021 (-1710 1800);
PAINT SKYBLUE (-1710 1800);
FORCEPROP 1 LAST PART_NUMBER G21796-016
J 0
(-1710 1700);
DISPLAY 0.617021 (-1710 1700);
PAINT BLUE (-1710 1700);
FORCEPROP 2 LAST CDS_LIB mstr_discrete
J 0
(-1750 1825);
PAINT MONO (-1750 1825);
DISPLAY INVISIBLE (-1750 1825);
FORCEPROP 1 LAST PATH I178
J 0
(-1700 2000);
DISPLAY 0.978723 (-1700 2000);
PAINT WHITE (-1700 2000);
DISPLAY INVISIBLE (-1700 2000);
FORCEPROP 2 LAST CDS_LOCATION R3T12
J 0
(-1705 1950);
DISPLAY 0.617021 (-1705 1950);
PAINT AQUA (-1705 1950);
DISPLAY INVISIBLE (-1705 1950);
FORCEPROP 2 LAST SEC_TYPE 0402
J 0
(-1700 2050);
DISPLAY 1.021277 (-1700 2050);
PAINT ORANGE (-1700 2050);
DISPLAY INVISIBLE (-1700 2050);
FORCEPROP 0 LAST BOM_COST MIO_BIOS_MEM
J 0
(-1700 2150);
DISPLAY 1.021277 (-1700 2150);
PAINT ORANGE (-1700 2150);
DISPLAY INVISIBLE (-1700 2150);
FORCEPROP 2 LAST SEC 1
J 0
(-1700 2050);
DISPLAY 0.680851 (-1700 2050);
PAINT MONO (-1700 2050);
DISPLAY INVISIBLE (-1700 2050);
FORCEPROP 0 LAST ROOM SB_SPI
J 0
(-1700 2050);
DISPLAY 1.021277 (-1700 2050);
PAINT ORANGE (-1700 2050);
DISPLAY INVISIBLE (-1700 2050);
FORCEADD RES..2
(-1750 1450);
FORCEPROP 1 LAST PACK_TYPE 0402
J 0
(-1710 1275);
DISPLAY 0.617021 (-1710 1275);
PAINT SKYBLUE (-1710 1275);
FORCEPROP 1 LASTPIN (-1750 1350) $PN 2
J 0
(-1745 1360);
DISPLAY 0.617021 (-1745 1360);
PAINT ORANGE (-1745 1360);
FORCEPROP 1 LAST WATTAGE 1/16W
J 0
(-1710 1425);
DISPLAY 0.617021 (-1710 1425);
PAINT SKYBLUE (-1710 1425);
FORCEPROP 1 LAST TOLERANCE 1%
J 0
(-1705 1475);
DISPLAY 0.617021 (-1705 1475);
PAINT SKYBLUE (-1705 1475);
FORCEPROP 1 LAST MATERIAL EMPTY
J 0
(-1710 1375);
DISPLAY 0.617021 (-1710 1375);
PAINT RED (-1710 1375);
FORCEPROP 1 LASTPIN (-1750 1550) $PN 1
J 0
(-1745 1512);
DISPLAY 0.617021 (-1745 1512);
PAINT ORANGE (-1745 1512);
FORCEPROP 1 LAST VALUE 10.0K
J 0
(-1705 1525);
DISPLAY 0.617021 (-1705 1525);
PAINT SKYBLUE (-1705 1525);
FORCEPROP 1 LAST LOCATION R3T9
J 0
(-1705 1575);
DISPLAY 0.617021 (-1705 1575);
PAINT AQUA (-1705 1575);
FORCEPROP 1 LAST PART_NUMBER G21796-016
J 0
(-1710 1325);
DISPLAY 0.617021 (-1710 1325);
PAINT BLUE (-1710 1325);
FORCEPROP 2 LAST CDS_LIB mstr_discrete
J 0
(-1750 1450);
PAINT MONO (-1750 1450);
DISPLAY INVISIBLE (-1750 1450);
FORCEPROP 2 LAST CDS_LOCATION R3T9
J 0
(-1705 1575);
DISPLAY 0.617021 (-1705 1575);
PAINT AQUA (-1705 1575);
DISPLAY INVISIBLE (-1705 1575);
FORCEPROP 1 LAST PATH I179
J 0
(-1700 1625);
DISPLAY 0.978723 (-1700 1625);
PAINT WHITE (-1700 1625);
DISPLAY INVISIBLE (-1700 1625);
FORCEPROP 0 LAST ROOM SB_SPI
J 0
(-1700 1675);
DISPLAY 1.021277 (-1700 1675);
PAINT ORANGE (-1700 1675);
DISPLAY INVISIBLE (-1700 1675);
FORCEPROP 2 LAST SEC 1
J 0
(-1700 1675);
DISPLAY 0.680851 (-1700 1675);
PAINT MONO (-1700 1675);
DISPLAY INVISIBLE (-1700 1675);
FORCEPROP 2 LAST SEC_TYPE 0402
J 0
(-1700 1675);
DISPLAY 1.021277 (-1700 1675);
PAINT ORANGE (-1700 1675);
DISPLAY INVISIBLE (-1700 1675);
FORCEPROP 0 LAST BOM_COST MIO_BIOS_MEM
J 0
(-1700 1775);
DISPLAY 1.021277 (-1700 1775);
PAINT ORANGE (-1700 1775);
DISPLAY INVISIBLE (-1700 1775);
FORCEADD GND..1
(-1750 1225);
FORCEPROP 3 LASTPIN (-1750 1275) SIG_NAME GND\g
J 0
(-1740 1285);
DISPLAY 0.659574 (-1740 1285);
PAINT MONO (-1740 1285);
DISPLAY INVISIBLE (-1740 1285);
FORCEPROP 1 LAST BODY_TYPE PLUMBING
J 0
(-1795 1182);
DISPLAY 0.340426 (-1795 1182);
PAINT GREEN (-1795 1182);
DISPLAY INVISIBLE (-1795 1182);
FORCEPROP 1 LAST VOLTAGE 0.0V
J 0
(-1795 1182);
DISPLAY 0.340426 (-1795 1182);
PAINT SKYBLUE (-1795 1182);
DISPLAY INVISIBLE (-1795 1182);
FORCEPROP 1 LAST PATH I180
J 0
(-1675 1225);
DISPLAY 0.872340 (-1675 1225);
PAINT AQUA (-1675 1225);
DISPLAY INVISIBLE (-1675 1225);
FORCEPROP 1 LAST SIZE 1B
J 0
(-1675 1175);
DISPLAY 0.872340 (-1675 1175);
PAINT AQUA (-1675 1175);
DISPLAY INVISIBLE (-1675 1175);
FORCEPROP 2 LAST CDS_LIB mstr_symbols
J 0
(-1750 1225);
PAINT MONO (-1750 1225);
DISPLAY INVISIBLE (-1750 1225);
FORCEPROP 1 LAST HDL_POWER GND
J 0
(-1750 1375);
DISPLAY 0.872340 (-1750 1375);
PAINT GREEN (-1750 1375);
DISPLAY INVISIBLE (-1750 1375);
FORCEADD RES..1
(-6525 3925);
FORCEPROP 1 LASTPIN (-6625 3925) $PN 1
J 0
(-6613 3937);
DISPLAY 0.617021 (-6613 3937);
PAINT MONO (-6613 3937);
FORCEPROP 1 LASTPIN (-6425 3925) $PN 2
J 0
(-6463 3937);
DISPLAY 0.617021 (-6463 3937);
PAINT MONO (-6463 3937);
FORCEPROP 1 LAST VALUE 33.2
J 2
(-6300 3932);
DISPLAY 0.617021 (-6300 3932);
PAINT SKYBLUE (-6300 3932);
FORCEPROP 1 LAST LOCATION R7F29
J 0
(-6532 3982);
DISPLAY 0.617021 (-6532 3982);
PAINT AQUA (-6532 3982);
FORCEPROP 1 LAST WATTAGE 1/16W
J 2
(-6550 3775);
PAINT SKYBLUE (-6550 3775);
DISPLAY INVISIBLE (-6550 3775);
FORCEPROP 1 LAST TOLERANCE 1%
J 0
(-6450 3775);
PAINT SKYBLUE (-6450 3775);
DISPLAY INVISIBLE (-6450 3775);
FORCEPROP 1 LAST PART_NUMBER G21796-074
J 0
(-6575 4025);
PAINT BLUE (-6575 4025);
DISPLAY INVISIBLE (-6575 4025);
FORCEPROP 2 LAST CDS_LOCATION R7F29
J 0
(-6532 3982);
DISPLAY 0.617021 (-6532 3982);
PAINT AQUA (-6532 3982);
DISPLAY INVISIBLE (-6532 3982);
FORCEPROP 2 LAST CDS_LIB mstr_discrete
J 1
(-6525 3925);
PAINT ORANGE (-6525 3925);
DISPLAY INVISIBLE (-6525 3925);
FORCEPROP 1 LAST PACK_TYPE 0402
J 0
(-6275 3775);
PAINT SKYBLUE (-6275 3775);
DISPLAY INVISIBLE (-6275 3775);
FORCEPROP 2 LAST ROOM SB_SPI
J 0
(-6300 3975);
DISPLAY 1.021277 (-6300 3975);
PAINT ORANGE (-6300 3975);
DISPLAY INVISIBLE (-6300 3975);
FORCEPROP 2 LAST BOM_COST MIO_BIOS_MEM
J 0
(-6300 4025);
DISPLAY 1.021277 (-6300 4025);
PAINT ORANGE (-6300 4025);
DISPLAY INVISIBLE (-6300 4025);
FORCEPROP 1 LAST MATERIAL CHIP
J 0
(-6325 3925);
PAINT SKYBLUE (-6325 3925);
DISPLAY INVISIBLE (-6325 3925);
FORCEPROP 1 LAST PATH I181
J 0
(-6575 4075);
DISPLAY 0.978723 (-6575 4075);
PAINT WHITE (-6575 4075);
DISPLAY INVISIBLE (-6575 4075);
FORCEPROP 2 LAST SEC 1
J 0
(-6575 4150);
DISPLAY 0.680851 (-6575 4150);
PAINT MONO (-6575 4150);
DISPLAY INVISIBLE (-6575 4150);
FORCEPROP 2 LAST SEC_TYPE 0402
J 0
(-6575 4150);
DISPLAY 1.021277 (-6575 4150);
PAINT ORANGE (-6575 4150);
DISPLAY INVISIBLE (-6575 4150);
FORCEADD OFFPAGE..1
(-7150 3925);
FORCEPROP 2 LAST $XR0 154 
J 0
(-7402 3925);
DISPLAY 0.638298 (-7402 3925);
PAINT MONO (-7402 3925);
FORCEPROP 2 LAST $XR1 153 
J 0
(-7522 3925);
DISPLAY 0.638298 (-7522 3925);
PAINT MONO (-7522 3925);
FORCEPROP 1 LAST COMMENT_BODY TRUE
J 0
(-7025 3825);
DISPLAY 0.872340 (-7025 3825);
PAINT GREEN (-7025 3825);
DISPLAY INVISIBLE (-7025 3825);
FORCEPROP 2 LAST CDS_LIB mstr_standard
J 0
(-7150 3925);
PAINT ORANGE (-7150 3925);
DISPLAY INVISIBLE (-7150 3925);
FORCEPROP 2 LAST PATH I182
J 0
(-7100 4000);
DISPLAY 1.021277 (-7100 4000);
PAINT ORANGE (-7100 4000);
DISPLAY INVISIBLE (-7100 4000);
FORCEPROP 1 LAST OFFPAGE TRUE
J 0
(-6825 3800);
DISPLAY 0.872340 (-6825 3800);
PAINT GREEN (-6825 3800);
DISPLAY INVISIBLE (-6825 3800);
FORCEADD OFFPAGE..1
(-7075 1825);
FORCEPROP 2 LAST $XR0 154 
J 0
(-7357 1825);
DISPLAY 0.638298 (-7357 1825);
PAINT MONO (-7357 1825);
FORCEPROP 2 LAST $XR1 153 
J 0
(-7477 1825);
DISPLAY 0.638298 (-7477 1825);
PAINT MONO (-7477 1825);
FORCEPROP 1 LAST COMMENT_BODY TRUE
J 0
(-6950 1725);
DISPLAY 0.872340 (-6950 1725);
PAINT GREEN (-6950 1725);
DISPLAY INVISIBLE (-6950 1725);
FORCEPROP 2 LAST CDS_LIB mstr_standard
J 0
(-7075 1825);
PAINT ORANGE (-7075 1825);
DISPLAY INVISIBLE (-7075 1825);
FORCEPROP 2 LAST PATH I183
J 0
(-7025 1900);
DISPLAY 1.021277 (-7025 1900);
PAINT ORANGE (-7025 1900);
DISPLAY INVISIBLE (-7025 1900);
FORCEPROP 1 LAST OFFPAGE TRUE
J 0
(-6750 1700);
DISPLAY 0.872340 (-6750 1700);
PAINT GREEN (-6750 1700);
DISPLAY INVISIBLE (-6750 1700);
FORCEADD RES..1
(-6450 1825);
FORCEPROP 1 LASTPIN (-6550 1825) $PN 1
J 0
(-6538 1837);
DISPLAY 0.617021 (-6538 1837);
PAINT MONO (-6538 1837);
FORCEPROP 1 LAST LOCATION R3T10
J 0
(-6457 1882);
DISPLAY 0.617021 (-6457 1882);
PAINT AQUA (-6457 1882);
FORCEPROP 1 LASTPIN (-6350 1825) $PN 2
J 0
(-6388 1837);
DISPLAY 0.617021 (-6388 1837);
PAINT MONO (-6388 1837);
FORCEPROP 1 LAST VALUE 33.2
J 2
(-6225 1832);
DISPLAY 0.617021 (-6225 1832);
PAINT SKYBLUE (-6225 1832);
FORCEPROP 1 LAST WATTAGE 1/16W
J 2
(-6475 1675);
PAINT SKYBLUE (-6475 1675);
DISPLAY INVISIBLE (-6475 1675);
FORCEPROP 1 LAST PART_NUMBER G21796-074
J 0
(-6500 1925);
PAINT BLUE (-6500 1925);
DISPLAY INVISIBLE (-6500 1925);
FORCEPROP 2 LAST CDS_LIB mstr_discrete
J 1
(-6450 1825);
PAINT ORANGE (-6450 1825);
DISPLAY INVISIBLE (-6450 1825);
FORCEPROP 2 LAST CDS_LOCATION R3T10
J 0
(-6457 1882);
DISPLAY 0.617021 (-6457 1882);
PAINT AQUA (-6457 1882);
DISPLAY INVISIBLE (-6457 1882);
FORCEPROP 1 LAST PATH I184
J 0
(-6500 1975);
DISPLAY 0.978723 (-6500 1975);
PAINT WHITE (-6500 1975);
DISPLAY INVISIBLE (-6500 1975);
FORCEPROP 1 LAST TOLERANCE 1%
J 0
(-6375 1675);
PAINT SKYBLUE (-6375 1675);
DISPLAY INVISIBLE (-6375 1675);
FORCEPROP 1 LAST PACK_TYPE 0402
J 0
(-6200 1675);
PAINT SKYBLUE (-6200 1675);
DISPLAY INVISIBLE (-6200 1675);
FORCEPROP 2 LAST ROOM SB_SPI
J 0
(-6225 1875);
DISPLAY 1.021277 (-6225 1875);
PAINT ORANGE (-6225 1875);
DISPLAY INVISIBLE (-6225 1875);
FORCEPROP 2 LAST BOM_COST MIO_BIOS_MEM
J 0
(-6225 1925);
DISPLAY 1.021277 (-6225 1925);
PAINT ORANGE (-6225 1925);
DISPLAY INVISIBLE (-6225 1925);
FORCEPROP 1 LAST MATERIAL CHIP
J 0
(-6250 1825);
PAINT SKYBLUE (-6250 1825);
DISPLAY INVISIBLE (-6250 1825);
FORCEPROP 2 LAST SEC_TYPE 0402
J 0
(-6500 2050);
DISPLAY 1.021277 (-6500 2050);
PAINT ORANGE (-6500 2050);
DISPLAY INVISIBLE (-6500 2050);
FORCEPROP 2 LAST SEC 1
J 0
(-6500 2050);
DISPLAY 0.680851 (-6500 2050);
PAINT MONO (-6500 2050);
DISPLAY INVISIBLE (-6500 2050);
FORCEADD RES..2
R 2
(-5950 4425);
FORCEPROP 1 LAST PART_NUMBER G21796-072
J 2
(-5990 4300);
DISPLAY 0.617021 (-5990 4300);
PAINT BLUE (-5990 4300);
FORCEPROP 1 LAST PACK_TYPE 0402
J 2
(-5990 4250);
DISPLAY 0.617021 (-5990 4250);
PAINT SKYBLUE (-5990 4250);
FORCEPROP 1 LASTPIN (-5950 4325) $PN 2
J 2
(-5955 4335);
DISPLAY 0.617021 (-5955 4335);
PAINT ORANGE (-5955 4335);
FORCEPROP 1 LAST WATTAGE 1/16W
J 2
(-5990 4350);
DISPLAY 0.617021 (-5990 4350);
PAINT SKYBLUE (-5990 4350);
FORCEPROP 1 LAST TOLERANCE 1%
J 2
(-5995 4400);
DISPLAY 0.617021 (-5995 4400);
PAINT SKYBLUE (-5995 4400);
FORCEPROP 1 LAST VALUE 4.75K
J 2
(-5995 4500);
DISPLAY 0.617021 (-5995 4500);
PAINT SKYBLUE (-5995 4500);
FORCEPROP 1 LAST LOCATION R7F6
J 2
(-5995 4550);
DISPLAY 0.617021 (-5995 4550);
PAINT AQUA (-5995 4550);
FORCEPROP 1 LAST MATERIAL EMPTY
J 2
(-5990 4450);
DISPLAY 0.617021 (-5990 4450);
PAINT RED (-5990 4450);
FORCEPROP 1 LASTPIN (-5950 4525) $PN 1
J 2
(-5955 4487);
DISPLAY 0.617021 (-5955 4487);
PAINT ORANGE (-5955 4487);
FORCEPROP 2 LAST CDS_LIB mstr_discrete
J 0
(-5950 4425);
PAINT ORANGE (-5950 4425);
DISPLAY INVISIBLE (-5950 4425);
FORCEPROP 2 LAST CDS_LOCATION R7F6
J 2
(-5995 4550);
DISPLAY 0.617021 (-5995 4550);
PAINT AQUA (-5995 4550);
DISPLAY INVISIBLE (-5995 4550);
FORCEPROP 2 LAST ROOM SB_SPI
J 0
(-5975 4600);
DISPLAY 1.021277 (-5975 4600);
PAINT ORANGE (-5975 4600);
DISPLAY INVISIBLE (-5975 4600);
FORCEPROP 1 LAST PATH I90
J 2
(-6000 4600);
DISPLAY 0.978723 (-6000 4600);
PAINT WHITE (-6000 4600);
DISPLAY INVISIBLE (-6000 4600);
FORCEPROP 2 LAST NO_XNET_CONNECTION 1
J 0
(-6000 4650);
PAINT MONO (-6000 4650);
DISPLAY INVISIBLE (-6000 4650);
FORCEPROP 2 LAST SEC 1
J 0
(-6000 4650);
DISPLAY 0.680851 (-6000 4650);
PAINT MONO (-6000 4650);
DISPLAY INVISIBLE (-6000 4650);
FORCEPROP 2 LAST SEC_TYPE 0402
J 0
(-6000 4650);
DISPLAY 1.021277 (-6000 4650);
PAINT ORANGE (-6000 4650);
DISPLAY INVISIBLE (-6000 4650);
FORCEPROP 2 LAST BOM_COST MIO_BIOS_MEM
J 0
(-5975 4650);
DISPLAY 1.021277 (-5975 4650);
PAINT ORANGE (-5975 4650);
DISPLAY INVISIBLE (-5975 4650);
FORCEADD GND..1
(-4150 3600);
FORCEPROP 3 LASTPIN (-4150 3650) SIG_NAME GND\g
J 0
(-4140 3660);
DISPLAY 0.659574 (-4140 3660);
PAINT MONO (-4140 3660);
DISPLAY INVISIBLE (-4140 3660);
FORCEPROP 1 LAST BODY_TYPE PLUMBING
J 0
(-4195 3557);
DISPLAY 0.340426 (-4195 3557);
PAINT GREEN (-4195 3557);
DISPLAY INVISIBLE (-4195 3557);
FORCEPROP 1 LAST VOLTAGE 0
J 0
(-4150 3600);
PAINT SKYBLUE (-4150 3600);
DISPLAY INVISIBLE (-4150 3600);
FORCEPROP 1 LAST HDL_POWER GND
J 0
(-4150 3750);
DISPLAY 1.170213 (-4150 3750);
PAINT GREEN (-4150 3750);
DISPLAY INVISIBLE (-4150 3750);
FORCEPROP 2 LAST CDS_LIB mstr_symbols
J 0
(-4150 3600);
PAINT ORANGE (-4150 3600);
DISPLAY INVISIBLE (-4150 3600);
FORCEPROP 1 LAST PATH I91
J 0
(-4075 3600);
DISPLAY 0.872340 (-4075 3600);
PAINT AQUA (-4075 3600);
DISPLAY INVISIBLE (-4075 3600);
FORCEPROP 1 LAST SIZE 1B
J 0
(-4075 3550);
DISPLAY 1.170213 (-4075 3550);
PAINT GREEN (-4075 3550);
DISPLAY INVISIBLE (-4075 3550);
FORCEADD RES..2
R 2
(-6250 4425);
FORCEPROP 1 LAST WATTAGE 1/16W
J 2
(-6290 4350);
DISPLAY 0.617021 (-6290 4350);
PAINT SKYBLUE (-6290 4350);
FORCEPROP 1 LAST PACK_TYPE 0402
J 2
(-6290 4250);
DISPLAY 0.617021 (-6290 4250);
PAINT SKYBLUE (-6290 4250);
FORCEPROP 1 LAST VALUE 4.75K
J 2
(-6295 4500);
DISPLAY 0.617021 (-6295 4500);
PAINT SKYBLUE (-6295 4500);
FORCEPROP 1 LAST PART_NUMBER G21796-072
J 2
(-6290 4300);
DISPLAY 0.617021 (-6290 4300);
PAINT BLUE (-6290 4300);
FORCEPROP 1 LAST LOCATION R7F5
J 2
(-6295 4550);
DISPLAY 0.617021 (-6295 4550);
PAINT AQUA (-6295 4550);
FORCEPROP 1 LASTPIN (-6250 4325) $PN 2
J 2
(-6255 4335);
DISPLAY 0.617021 (-6255 4335);
PAINT ORANGE (-6255 4335);
FORCEPROP 1 LASTPIN (-6250 4525) $PN 1
J 2
(-6255 4487);
DISPLAY 0.617021 (-6255 4487);
PAINT ORANGE (-6255 4487);
FORCEPROP 1 LAST TOLERANCE 1%
J 2
(-6295 4400);
DISPLAY 0.617021 (-6295 4400);
PAINT SKYBLUE (-6295 4400);
FORCEPROP 1 LAST MATERIAL CHIP
J 2
(-6290 4450);
DISPLAY 0.617021 (-6290 4450);
PAINT SKYBLUE (-6290 4450);
FORCEPROP 2 LAST CDS_LOCATION R7F5
J 2
(-6295 4550);
DISPLAY 0.617021 (-6295 4550);
PAINT AQUA (-6295 4550);
DISPLAY INVISIBLE (-6295 4550);
FORCEPROP 2 LAST CDS_LIB mstr_discrete
J 0
(-6250 4425);
PAINT ORANGE (-6250 4425);
DISPLAY INVISIBLE (-6250 4425);
FORCEPROP 2 LAST ROOM SB_SPI
J 0
(-6275 4600);
DISPLAY 1.021277 (-6275 4600);
PAINT ORANGE (-6275 4600);
DISPLAY INVISIBLE (-6275 4600);
FORCEPROP 1 LAST PATH I94
J 2
(-6300 4600);
DISPLAY 0.978723 (-6300 4600);
PAINT WHITE (-6300 4600);
DISPLAY INVISIBLE (-6300 4600);
FORCEPROP 2 LAST SEC_TYPE 0402
J 0
(-6300 4650);
DISPLAY 1.021277 (-6300 4650);
PAINT ORANGE (-6300 4650);
DISPLAY INVISIBLE (-6300 4650);
FORCEPROP 2 LAST BOM_COST MIO_BIOS_MEM
J 0
(-6275 4650);
DISPLAY 1.021277 (-6275 4650);
PAINT ORANGE (-6275 4650);
DISPLAY INVISIBLE (-6275 4650);
FORCEPROP 2 LAST SEC 1
J 0
(-6300 4650);
DISPLAY 0.680851 (-6300 4650);
PAINT MONO (-6300 4650);
DISPLAY INVISIBLE (-6300 4650);
FORCEPROP 2 LAST NO_XNET_CONNECTION 1
J 0
(-6300 4650);
PAINT MONO (-6300 4650);
DISPLAY INVISIBLE (-6300 4650);
FORCEADD P3V3_STBY..1
(-6450 4825);
FORCEPROP 3 LASTPIN (-6450 4775) SIG_NAME P3V3_STBY\g
J 0
(-6440 4785);
DISPLAY 0.659574 (-6440 4785);
PAINT MONO (-6440 4785);
DISPLAY INVISIBLE (-6440 4785);
FORCEPROP 1 LAST HDL_POWER P3V3_STBY
J 0
(-6750 4700);
DISPLAY 0.872340 (-6750 4700);
PAINT ORANGE (-6750 4700);
DISPLAY INVISIBLE (-6750 4700);
FORCEPROP 1 LAST VOLTAGE 3.3V
J 0
(-6495 4782);
DISPLAY 0.340426 (-6495 4782);
PAINT SKYBLUE (-6495 4782);
DISPLAY INVISIBLE (-6495 4782);
FORCEPROP 2 LAST CDS_LIB mstr_symbols
J 0
(-6450 4825);
PAINT ORANGE (-6450 4825);
DISPLAY INVISIBLE (-6450 4825);
FORCEPROP 1 LAST SIZE 1B
J 0
(-6405 4847);
DISPLAY 0.340426 (-6405 4847);
PAINT GREEN (-6405 4847);
DISPLAY INVISIBLE (-6405 4847);
FORCEPROP 1 LAST BODY_TYPE PLUMBING
J 0
(-6495 4782);
DISPLAY 0.340426 (-6495 4782);
PAINT GREEN (-6495 4782);
DISPLAY INVISIBLE (-6495 4782);
FORCEPROP 1 LAST PATH I95
J 0
(-6405 4827);
DISPLAY 0.340426 (-6405 4827);
PAINT GREEN (-6405 4827);
DISPLAY INVISIBLE (-6405 4827);
FORCEADD RES..1
(-6275 3975);
FORCEPROP 1 LASTPIN (-6375 3975) $PN 1
J 0
(-6363 3987);
DISPLAY 0.617021 (-6363 3987);
PAINT MONO (-6363 3987);
FORCEPROP 1 LASTPIN (-6175 3975) $PN 2
J 0
(-6213 3987);
DISPLAY 0.617021 (-6213 3987);
PAINT MONO (-6213 3987);
FORCEPROP 1 LAST VALUE 33.2
J 2
(-6050 3982);
DISPLAY 0.617021 (-6050 3982);
PAINT SKYBLUE (-6050 3982);
FORCEPROP 1 LAST LOCATION R7F4
J 0
(-6157 3932);
DISPLAY 0.617021 (-6157 3932);
PAINT AQUA (-6157 3932);
FORCEPROP 1 LAST TOLERANCE 1%
J 0
(-6200 3825);
PAINT SKYBLUE (-6200 3825);
DISPLAY INVISIBLE (-6200 3825);
FORCEPROP 1 LAST WATTAGE 1/16W
J 2
(-6300 3825);
PAINT SKYBLUE (-6300 3825);
DISPLAY INVISIBLE (-6300 3825);
FORCEPROP 2 LAST CDS_LIB mstr_discrete
J 1
(-6275 3975);
PAINT ORANGE (-6275 3975);
DISPLAY INVISIBLE (-6275 3975);
FORCEPROP 2 LAST CDS_LOCATION R7F4
J 0
(-6157 3932);
DISPLAY 0.617021 (-6157 3932);
PAINT AQUA (-6157 3932);
DISPLAY INVISIBLE (-6157 3932);
FORCEPROP 1 LAST PACK_TYPE 0402
J 0
(-6025 3825);
PAINT SKYBLUE (-6025 3825);
DISPLAY INVISIBLE (-6025 3825);
FORCEPROP 1 LAST MATERIAL CHIP
J 0
(-6075 3975);
PAINT SKYBLUE (-6075 3975);
DISPLAY INVISIBLE (-6075 3975);
FORCEPROP 2 LAST ROOM SB_SPI
J 0
(-6050 4025);
DISPLAY 1.021277 (-6050 4025);
PAINT ORANGE (-6050 4025);
DISPLAY INVISIBLE (-6050 4025);
FORCEPROP 2 LAST BOM_COST MIO_BIOS_MEM
J 0
(-6050 4075);
DISPLAY 1.021277 (-6050 4075);
PAINT ORANGE (-6050 4075);
DISPLAY INVISIBLE (-6050 4075);
FORCEPROP 1 LAST PART_NUMBER G21796-074
J 0
(-6325 4075);
PAINT BLUE (-6325 4075);
DISPLAY INVISIBLE (-6325 4075);
FORCEPROP 1 LAST PATH I98
J 0
(-6325 4125);
DISPLAY 0.978723 (-6325 4125);
PAINT WHITE (-6325 4125);
DISPLAY INVISIBLE (-6325 4125);
FORCEPROP 2 LAST SEC 1
J 0
(-6325 4200);
DISPLAY 0.680851 (-6325 4200);
PAINT MONO (-6325 4200);
DISPLAY INVISIBLE (-6325 4200);
FORCEPROP 2 LAST SEC_TYPE 0402
J 0
(-6325 4200);
DISPLAY 1.021277 (-6325 4200);
PAINT ORANGE (-6325 4200);
DISPLAY INVISIBLE (-6325 4200);
FORCEADD BOM_NOTE..1
(-4700 850);
FORCEPROP 0 LAST L1 SOCKET IS D91187-001
J 0
(-4850 750);
DISPLAY 0.617021 (-4850 750);
PAINT WHITE (-4850 750);
FORCEPROP 1 LAST COMMENT_BODY TRUE
J 0
(-4675 950);
DISPLAY 1.319149 (-4675 950);
PAINT WHITE (-4675 950);
DISPLAY INVISIBLE (-4675 950);
FORCEPROP 2 LAST CDS_LIB mstr_symbols
J 0
(-4700 850);
PAINT WHITE (-4700 850);
DISPLAY INVISIBLE (-4700 850);
FORCEADD CAD_NOTE..1
(-4700 1150);
FORCEPROP 0 LAST L2 USE ALT SYMBOL ASSOCIATED WITH PART FOOTPRINT
J 0
(-4850 1000);
DISPLAY 0.617021 (-4850 1000);
PAINT WHITE (-4850 1000);
FORCEPROP 0 LAST L1 THIS PART WILL BE IN SOCKET, PLEASE
J 0
(-4850 1050);
DISPLAY 0.617021 (-4850 1050);
PAINT WHITE (-4850 1050);
FORCEPROP 1 LAST COMMENT_BODY TRUE
J 0
(-4675 1250);
DISPLAY 1.319149 (-4675 1250);
PAINT WHITE (-4675 1250);
DISPLAY INVISIBLE (-4675 1250);
FORCEPROP 2 LAST CDS_LIB mstr_symbols
J 0
(-4700 1150);
PAINT WHITE (-4700 1150);
DISPLAY INVISIBLE (-4700 1150);
FORCEADD CAD_NOTE..1
(-3150 2350);
FORCEPROP 0 LAST L1 PLACE CAPS NEAR VCC PIN ON W25Q256 COMPONENT
J 0
(-3300 2225);
DISPLAY 0.808511 (-3300 2225);
PAINT ORANGE (-3300 2225);
FORCEPROP 2 LAST CDS_LIB mstr_symbols
J 0
(-3150 2350);
PAINT ORANGE (-3150 2350);
DISPLAY INVISIBLE (-3150 2350);
FORCEPROP 1 LAST COMMENT_BODY TRUE
J 0
(-3125 2450);
DISPLAY 0.978723 (-3125 2450);
PAINT ORANGE (-3125 2450);
DISPLAY INVISIBLE (-3125 2450);
FORCEADD BOM_NOTE..1
(-4825 3000);
FORCEPROP 0 LAST L1 SOCKET IS D91187-001
J 0
(-4975 2900);
DISPLAY 0.617021 (-4975 2900);
PAINT WHITE (-4975 2900);
FORCEPROP 2 LAST CDS_LIB mstr_symbols
J 0
(-4825 3000);
PAINT WHITE (-4825 3000);
DISPLAY INVISIBLE (-4825 3000);
FORCEPROP 1 LAST COMMENT_BODY TRUE
J 0
(-4800 3100);
DISPLAY 1.319149 (-4800 3100);
PAINT WHITE (-4800 3100);
DISPLAY INVISIBLE (-4800 3100);
FORCEADD CAD_NOTE..1
(-3275 4550);
FORCEPROP 0 LAST L1 PLACE CAPS NEAR VCC PIN ON W25Q256 COMPONENT
J 0
(-3425 4425);
DISPLAY 0.808511 (-3425 4425);
PAINT ORANGE (-3425 4425);
FORCEPROP 1 LAST COMMENT_BODY TRUE
J 0
(-3250 4650);
DISPLAY 0.978723 (-3250 4650);
PAINT ORANGE (-3250 4650);
DISPLAY INVISIBLE (-3250 4650);
FORCEPROP 2 LAST CDS_LIB mstr_symbols
J 0
(-3275 4550);
PAINT ORANGE (-3275 4550);
DISPLAY INVISIBLE (-3275 4550);
FORCEADD CAD_NOTE..1
(-4825 3300);
FORCEPROP 0 LAST L2 USE ALT SYMBOL ASSOCIATED WITH PART FOOTPRINT
J 0
(-4975 3150);
DISPLAY 0.617021 (-4975 3150);
PAINT WHITE (-4975 3150);
FORCEPROP 0 LAST L1 THIS PART WILL BE IN SOCKET, PLEASE
J 0
(-4975 3200);
DISPLAY 0.617021 (-4975 3200);
PAINT WHITE (-4975 3200);
FORCEPROP 1 LAST COMMENT_BODY TRUE
J 0
(-4800 3400);
DISPLAY 1.319149 (-4800 3400);
PAINT WHITE (-4800 3400);
DISPLAY INVISIBLE (-4800 3400);
FORCEPROP 2 LAST CDS_LIB mstr_symbols
J 0
(-4825 3300);
PAINT WHITE (-4825 3300);
DISPLAY INVISIBLE (-4825 3300);
FORCEADD DNS..2
(-5870 2320);
PAINT RED (-5870 2320);
FORCEPROP 1 LAST COMMENT_BODY TRUE
R 1
J 0
(-5795 2095);
DISPLAY 0.872340 (-5795 2095);
PAINT GREEN (-5795 2095);
DISPLAY INVISIBLE (-5795 2095);
FORCEPROP 2 LAST CDS_LIB mstr_misc
J 0
(-5870 2320);
PAINT ORANGE (-5870 2320);
DISPLAY INVISIBLE (-5870 2320);
FORCEADD DESIGN_NOTE..1
(-3250 1150);
FORCEPROP 0 LAST L3 SOLDERED DIRECTLY TO THE BOARD
J 0
(-3450 875);
DISPLAY 0.808511 (-3450 875);
PAINT ORANGE (-3450 875);
FORCEPROP 0 LAST L1 SECONDARY FLASH WILL BE SOCKETED ON DOUBLE-SIDED SKU
J 0
(-3450 1025);
DISPLAY 0.808511 (-3450 1025);
PAINT ORANGE (-3450 1025);
FORCEPROP 0 LAST L2 FOR SINGLE-SIDED SKU, SECONDARY FLASH WILL BE
J 0
(-3450 950);
DISPLAY 0.808511 (-3450 950);
PAINT ORANGE (-3450 950);
FORCEPROP 2 LAST CDS_LIB mstr_symbols
J 0
(-3250 1150);
PAINT MONO (-3250 1150);
DISPLAY INVISIBLE (-3250 1150);
FORCEPROP 1 LAST COMMENT_BODY TRUE
J 0
(-3225 1250);
DISPLAY 0.978723 (-3225 1250);
PAINT ORANGE (-3225 1250);
DISPLAY INVISIBLE (-3225 1250);
FORCEADD DNS..2
(-1745 3545);
PAINT RED (-1745 3545);
FORCEPROP 1 LAST COMMENT_BODY TRUE
R 1
J 0
(-1670 3320);
DISPLAY 0.872340 (-1670 3320);
PAINT GREEN (-1670 3320);
DISPLAY INVISIBLE (-1670 3320);
FORCEPROP 2 LAST CDS_LIB mstr_misc
J 0
(-1745 3545);
PAINT ORANGE (-1745 3545);
DISPLAY INVISIBLE (-1745 3545);
FORCEADD DNS..2
(-1745 1445);
PAINT RED (-1745 1445);
FORCEPROP 1 LAST COMMENT_BODY TRUE
R 1
J 0
(-1670 1220);
DISPLAY 0.872340 (-1670 1220);
PAINT GREEN (-1670 1220);
DISPLAY INVISIBLE (-1670 1220);
FORCEPROP 2 LAST CDS_LIB mstr_misc
J 0
(-1745 1445);
PAINT ORANGE (-1745 1445);
DISPLAY INVISIBLE (-1745 1445);
FORCEADD DESIGN_NOTE..1
(-3200 3925);
FORCEPROP 0 LAST L4 MICRON MT25QL512ABA8ESF
J 0
(-3400 3425);
DISPLAY 1.021277 (-3400 3425);
PAINT ORANGE (-3400 3425);
FORCEPROP 0 LAST L3 64MB FLASH = H60781-001
J 0
(-3400 3500);
DISPLAY 1.021277 (-3400 3500);
PAINT ORANGE (-3400 3500);
FORCEPROP 0 LAST L1 32MB FLASH = H25002-001
J 0
(-3400 3800);
DISPLAY 1.021277 (-3400 3800);
PAINT ORANGE (-3400 3800);
FORCEPROP 0 LAST L2 WINBOND W25Q256FVFIQ
J 0
(-3400 3700);
DISPLAY 1.021277 (-3400 3700);
PAINT ORANGE (-3400 3700);
FORCEPROP 1 LAST COMMENT_BODY TRUE
J 0
(-3175 4025);
DISPLAY 0.978723 (-3175 4025);
PAINT ORANGE (-3175 4025);
DISPLAY INVISIBLE (-3175 4025);
FORCEPROP 2 LAST CDS_LIB mstr_symbols
J 0
(-3200 3925);
PAINT ORANGE (-3200 3925);
DISPLAY INVISIBLE (-3200 3925);
FORCEADD DNS..2
(-5945 4420);
PAINT RED (-5945 4420);
FORCEPROP 1 LAST COMMENT_BODY TRUE
R 1
J 0
(-5870 4195);
DISPLAY 0.872340 (-5870 4195);
PAINT GREEN (-5870 4195);
DISPLAY INVISIBLE (-5870 4195);
FORCEPROP 2 LAST CDS_LIB mstr_misc
J 0
(-5945 4420);
PAINT ORANGE (-5945 4420);
DISPLAY INVISIBLE (-5945 4420);
FORCEADD INTEL_CORP_BPAGE..1
(0 0);
FORCEPROP 1 LAST CDS_CON_LAST_MODIFIED Tue Dec 01 11:52:08 2015
J 0
(-1425 325);
DISPLAY 1.361702 (-1425 325);
PAINT GREEN (-1425 325);
DISPLAY INVISIBLE (-1425 325);
FORCEPROP 1 LAST CUSTOM_TXT_CDS <CURRENT_DESIGN_SHEET> OF <TOTAL_DESIGN_SHEETS>
J 0
(-500 25);
PAINT GREEN (-500 25);
FORCEPROP 1 LAST CUSTOM_TXT_CDS <CON_LAST_MODIFIED>
J 0
(-1925 350);
PAINT GREEN (-1925 350);
FORCEPROP 2 LAST CUSTOM_TXT_CDS <XR_PAGE_TITLE>
J 0
(-7890 5250);
DISPLAY 0.638298 (-7890 5250);
PAINT PINK (-7890 5250);
DISPLAY INVISIBLE (-7890 5250);
FORCEPROP 1 LAST SCH_TITLE BMC AND PCH SHARED SPI FLASH
J 0
(-7950 50);
DISPLAY 1.212766 (-7950 50);
PAINT ORANGE (-7950 50);
FORCEPROP 1 LAST SCH_ADDRESS3 Santa Clara, CA 95052-8119
J 0
(-3975 25);
DISPLAY 0.617021 (-3975 25);
PAINT GREEN (-3975 25);
FORCEPROP 1 LAST SCH_ADDRESS2 P.O. BOX 58119
J 0
(-3975 75);
DISPLAY 0.617021 (-3975 75);
PAINT GREEN (-3975 75);
FORCEPROP 1 LAST SCH_ADDRESS1 2200 Mission College Blvd.
J 0
(-3975 125);
DISPLAY 0.617021 (-3975 125);
PAINT GREEN (-3975 125);
FORCEPROP 1 LAST SCH_NUMBER H4694802
J 0
(-1300 150);
DISPLAY 1.212766 (-1300 150);
PAINT YELLOW (-1300 150);
FORCEPROP 1 LAST SCH_DEPT BESD
J 1
(-4450 100);
DISPLAY 1.212766 (-4450 100);
PAINT YELLOW (-4450 100);
FORCEPROP 1 LAST SCH_REV 2.420
J 0
(-250 150);
DISPLAY 0.978723 (-250 150);
PAINT YELLOW (-250 150);
FORCEPROP 2 LAST PAGE_BORDER TRUE
J 0
(-7890 5250);
DISPLAY 0.851064 (-7890 5250);
PAINT PINK (-7890 5250);
DISPLAY INVISIBLE (-7890 5250);
FORCEPROP 2 LAST CDS_LIB mstr_symbols
J 0
(0 0);
DISPLAY 1.361702 (0 0);
PAINT ORANGE (0 0);
DISPLAY INVISIBLE (0 0);
FORCEPROP 1 LAST COMMENT_BODY TRUE
J 0
(12 12);
DISPLAY 0.617021 (12 12);
PAINT GREEN (12 12);
DISPLAY INVISIBLE (12 12);
FORCEPROP 2 LAST CDS_XR_PAGE_TITLE CR-153 : @BASEBOARD_FAB2_LIB.BASEBOARD_FAB2(SCH_1):PAGE153
J 0
(-7890 5250);
DISPLAY 0.638298 (-7890 5250);
PAINT PINK (-7890 5250);
DISPLAY INVISIBLE (-7890 5250);
WIRE 16 -1 (-3775 4300)(-4075 4300);
WIRE 16 -1 (-3775 4400)(-3775 4300);
WIRE 16 -1 (-3775 4225)(-3775 4300);
WIRE 16 -1 (-4075 4300)(-4075 4400);
WIRE 16 -1 (-3625 2200)(-3925 2200);
WIRE 16 -1 (-3625 2300)(-3625 2200);
WIRE 16 -1 (-3625 2150)(-3625 2200);
WIRE 16 -1 (-3925 2200)(-3925 2300);
WIRE 16 -1 (-1550 4425)(-1750 4425);
WIRE 16 -1 (-1750 4425)(-1750 4575);
WIRE 16 -1 (-3625 2500)(-3625 2550);
WIRE 16 -1 (-3625 2550)(-3925 2550);
WIRE 16 -1 (-3925 2550)(-3925 2500);
WIRE 16 -1 (-5525 2550)(-3925 2550);
WIRE 16 -1 (-5525 2550)(-5525 2075);
WIRE 16 -1 (-5525 2550)(-5875 2550);
WIRE 16 -1 (-5875 2425)(-5875 2550);
WIRE 16 -1 (-6175 2550)(-5875 2550);
WIRE 16 -1 (-5525 2075)(-5375 2075);
WIRE 16 -1 (-6175 2425)(-6175 2550);
WIRE 16 -1 (-6375 2550)(-6175 2550);
WIRE 16 -1 (-6375 2675)(-6375 2550);
WIRE 16 -1 (-4275 1625)(-4075 1625);
WIRE 16 -1 (-4075 1625)(-4075 1550);
WIRE 16 -1 (-1750 4125)(-1750 4025);
WIRE 16 -1 (-1750 3375)(-1750 3450);
WIRE 16 -1 (-1550 2325)(-1750 2325);
WIRE 16 -1 (-1750 2325)(-1750 2475);
WIRE 16 -1 (-1750 2025)(-1750 1925);
WIRE 16 -1 (-1750 1275)(-1750 1350);
WIRE 16 -1 (-4350 3725)(-4150 3725);
WIRE 16 -1 (-4150 3725)(-4150 3650);
WIRE 16 -1 (-3775 4600)(-3775 4650);
WIRE 16 -1 (-3775 4650)(-4075 4650);
WIRE 16 -1 (-4075 4650)(-4075 4600);
WIRE 16 -1 (-5600 4650)(-4075 4650);
WIRE 16 -1 (-5600 4650)(-5600 4175);
WIRE 16 -1 (-5600 4650)(-5950 4650);
WIRE 16 -1 (-5950 4525)(-5950 4650);
WIRE 16 -1 (-6250 4650)(-5950 4650);
WIRE 16 -1 (-5600 4175)(-5450 4175);
WIRE 16 -1 (-6250 4525)(-6250 4650);
WIRE 16 -1 (-6450 4650)(-6250 4650);
WIRE 16 -1 (-6450 4775)(-6450 4650);
WIRE 16 -1 (-1350 4425)(-725 4425);
FORCEPROP 2 LAST SIG_NAME PU_BIOS_SPI_HOLD0_N
J 2
(-750 4435);
DISPLAY 0.617021 (-750 4435);
PAINT ORANGE (-750 4435);
WIRE 16 -1 (-1750 3750)(-700 3750);
FORCEPROP 2 LAST SIG_NAME PU_BIOS_SPI_WP0_N
J 2
(-750 3760);
DISPLAY 0.617021 (-750 3760);
PAINT ORANGE (-750 3760);
WIRE 16 -1 (-1750 3750)(-1750 3825);
WIRE 16 -1 (-1750 3650)(-1750 3750);
WIRE 16 -1 (-1350 2325)(-725 2325);
FORCEPROP 2 LAST SIG_NAME PU_BIOS_SPI_HOLD1_N
J 2
(-750 2335);
DISPLAY 0.617021 (-750 2335);
PAINT ORANGE (-750 2335);
WIRE 16 -1 (-1750 1650)(-700 1650);
FORCEPROP 2 LAST SIG_NAME PU_BIOS_SPI_WP1_N
J 2
(-750 1660);
DISPLAY 0.617021 (-750 1660);
PAINT ORANGE (-750 1660);
WIRE 16 -1 (-1750 1650)(-1750 1725);
WIRE 16 -1 (-1750 1550)(-1750 1650);
WIRE 16 -1 (-3800 1825)(-4275 1825);
FORCEPROP 2 LAST SIG_NAME TP_SPI_1_1
J 0
(-4210 1835);
DISPLAY 0.617021 (-4210 1835);
PAINT ORANGE (-4210 1835);
FORCEPROP 2 LASTPROP $XRERR UNIQUE?
J 0
(-3770 1825);
DISPLAY 0.638298 (-3770 1825);
PAINT MONO (-3770 1825);
DISPLAY INVISIBLE (-3770 1825);
WIRE 16 -1 (-3800 2025)(-4275 2025);
FORCEPROP 2 LAST SIG_NAME TP_SPI_1_5
J 0
(-4210 2035);
DISPLAY 0.617021 (-4210 2035);
PAINT ORANGE (-4210 2035);
FORCEPROP 2 LASTPROP $XRERR UNIQUE?
J 0
(-3770 2025);
DISPLAY 0.638298 (-3770 2025);
PAINT MONO (-3770 2025);
DISPLAY INVISIBLE (-3770 2025);
WIRE 16 -1 (-3875 3925)(-4350 3925);
FORCEPROP 2 LAST SIG_NAME TP_SPI_0_1
J 0
(-4285 3935);
DISPLAY 0.617021 (-4285 3935);
PAINT ORANGE (-4285 3935);
FORCEPROP 2 LASTPROP $XRERR UNIQUE?
J 0
(-3845 3925);
DISPLAY 0.638298 (-3845 3925);
PAINT MONO (-3845 3925);
DISPLAY INVISIBLE (-3845 3925);
WIRE 16 -1 (-3875 3875)(-4350 3875);
FORCEPROP 2 LAST SIG_NAME TP_SPI_0_0
J 0
(-4285 3885);
DISPLAY 0.617021 (-4285 3885);
PAINT ORANGE (-4285 3885);
FORCEPROP 2 LASTPROP $XRERR UNIQUE?
J 0
(-3845 3875);
DISPLAY 0.638298 (-3845 3875);
PAINT MONO (-3845 3875);
DISPLAY INVISIBLE (-3845 3875);
WIRE 16 -1 (-3875 3975)(-4350 3975);
FORCEPROP 2 LAST SIG_NAME TP_SPI_0_2
J 0
(-4285 3985);
DISPLAY 0.617021 (-4285 3985);
PAINT ORANGE (-4285 3985);
FORCEPROP 2 LASTPROP $XRERR UNIQUE?
J 0
(-3845 3975);
DISPLAY 0.638298 (-3845 3975);
PAINT MONO (-3845 3975);
DISPLAY INVISIBLE (-3845 3975);
WIRE 16 -1 (-3800 1775)(-4275 1775);
FORCEPROP 2 LAST SIG_NAME TP_SPI_1_0
J 0
(-4210 1785);
DISPLAY 0.617021 (-4210 1785);
PAINT ORANGE (-4210 1785);
FORCEPROP 2 LASTPROP $XRERR UNIQUE?
J 0
(-3770 1775);
DISPLAY 0.638298 (-3770 1775);
PAINT MONO (-3770 1775);
DISPLAY INVISIBLE (-3770 1775);
WIRE 16 -1 (-3800 2075)(-4275 2075);
FORCEPROP 2 LAST SIG_NAME TP_SPI_1_6
J 0
(-4210 2085);
DISPLAY 0.617021 (-4210 2085);
PAINT ORANGE (-4210 2085);
FORCEPROP 2 LASTPROP $XRERR UNIQUE?
J 0
(-3770 2075);
DISPLAY 0.638298 (-3770 2075);
PAINT MONO (-3770 2075);
DISPLAY INVISIBLE (-3770 2075);
WIRE 16 -1 (-3875 4025)(-4350 4025);
FORCEPROP 2 LAST SIG_NAME TP_SPI_0_3
J 0
(-4285 4035);
DISPLAY 0.617021 (-4285 4035);
PAINT ORANGE (-4285 4035);
FORCEPROP 2 LASTPROP $XRERR UNIQUE?
J 0
(-3845 4025);
DISPLAY 0.638298 (-3845 4025);
PAINT MONO (-3845 4025);
DISPLAY INVISIBLE (-3845 4025);
WIRE 16 -1 (-3875 4125)(-4350 4125);
FORCEPROP 2 LAST SIG_NAME TP_SPI_0_5
J 0
(-4285 4135);
DISPLAY 0.617021 (-4285 4135);
PAINT ORANGE (-4285 4135);
FORCEPROP 2 LASTPROP $XRERR UNIQUE?
J 0
(-3845 4125);
DISPLAY 0.638298 (-3845 4125);
PAINT MONO (-3845 4125);
DISPLAY INVISIBLE (-3845 4125);
WIRE 16 -1 (-3875 4175)(-4350 4175);
FORCEPROP 2 LAST SIG_NAME TP_SPI_0_6
J 0
(-4285 4185);
DISPLAY 0.617021 (-4285 4185);
PAINT ORANGE (-4285 4185);
FORCEPROP 2 LASTPROP $XRERR UNIQUE?
J 0
(-3845 4175);
DISPLAY 0.638298 (-3845 4175);
PAINT MONO (-3845 4175);
DISPLAY INVISIBLE (-3845 4175);
WIRE 16 -1 (-3800 1875)(-4275 1875);
FORCEPROP 2 LAST SIG_NAME TP_SPI_1_2
J 0
(-4210 1885);
DISPLAY 0.617021 (-4210 1885);
PAINT ORANGE (-4210 1885);
FORCEPROP 2 LASTPROP $XRERR UNIQUE?
J 0
(-3770 1875);
DISPLAY 0.638298 (-3770 1875);
PAINT MONO (-3770 1875);
DISPLAY INVISIBLE (-3770 1875);
WIRE 16 -1 (-3800 1925)(-4275 1925);
FORCEPROP 2 LAST SIG_NAME TP_SPI_1_3
J 0
(-4210 1935);
DISPLAY 0.617021 (-4210 1935);
PAINT ORANGE (-4210 1935);
FORCEPROP 2 LASTPROP $XRERR UNIQUE?
J 0
(-3770 1925);
DISPLAY 0.638298 (-3770 1925);
PAINT MONO (-3770 1925);
DISPLAY INVISIBLE (-3770 1925);
WIRE 16 -1 (-3800 1975)(-4275 1975);
FORCEPROP 2 LAST SIG_NAME TP_SPI_1_4
J 0
(-4210 1985);
DISPLAY 0.617021 (-4210 1985);
PAINT ORANGE (-4210 1985);
FORCEPROP 2 LASTPROP $XRERR UNIQUE?
J 0
(-3770 1975);
DISPLAY 0.638298 (-3770 1975);
PAINT MONO (-3770 1975);
DISPLAY INVISIBLE (-3770 1975);
WIRE 16 -1 (-3875 4075)(-4350 4075);
FORCEPROP 2 LAST SIG_NAME TP_SPI_0_4
J 0
(-4285 4085);
DISPLAY 0.617021 (-4285 4085);
PAINT ORANGE (-4285 4085);
FORCEPROP 2 LASTPROP $XRERR UNIQUE?
J 0
(-3845 4075);
DISPLAY 0.638298 (-3845 4075);
PAINT MONO (-3845 4075);
DISPLAY INVISIBLE (-3845 4075);
WIRE 16 -1 (-6250 4325)(-6250 3725);
WIRE 16 -1 (-5450 3725)(-6250 3725);
WIRE 16 -1 (-6250 3725)(-7100 3725);
FORCEPROP 2 LAST SIG_NAME SPI_CS0_PRIMARY_R_N
J 0
(-7100 3735);
DISPLAY 0.617021 (-7100 3735);
PAINT ORANGE (-7100 3735);
WIRE 16 -1 (-5950 4325)(-5950 3675);
WIRE 16 -1 (-5950 3675)(-5450 3675);
FORCEPROP 0 LAST SIG_NAME PU_SPI0_RST
J 0
(-5860 3685);
DISPLAY 0.617021 (-5860 3685);
PAINT ORANGE (-5860 3685);
FORCEPROP 2 LASTPROP $XRERR UNIQUE?
J 0
(-6100 3685);
DISPLAY 0.638298 (-6100 3685);
PAINT MONO (-6100 3685);
DISPLAY INVISIBLE (-6100 3685);
WIRE 16 -1 (-5900 4075)(-5450 4075);
WIRE 16 -1 (-5900 3325)(-5900 4075);
WIRE 16 -1 (-7100 4075)(-5900 4075);
FORCEPROP 2 LAST SIG_NAME PU_BIOS_SPI_HOLD0_N
J 0
(-7100 4085);
DISPLAY 0.617021 (-7100 4085);
PAINT ORANGE (-7100 4085);
WIRE 16 -1 (-6375 3325)(-5900 3325);
WIRE 16 -1 (-6000 4025)(-5450 4025);
WIRE 16 -1 (-6000 3600)(-6000 4025);
WIRE 16 -1 (-7100 4025)(-6000 4025);
FORCEPROP 2 LAST SIG_NAME PU_BIOS_SPI_WP0_N
J 0
(-7100 4035);
DISPLAY 0.617021 (-7100 4035);
PAINT ORANGE (-7100 4035);
WIRE 16 -1 (-6400 3600)(-6000 3600);
WIRE 16 -1 (-5875 2225)(-5875 1575);
WIRE 16 -1 (-5875 1575)(-5375 1575);
FORCEPROP 0 LAST SIG_NAME PU_SPI1_RST
J 0
(-5760 1585);
DISPLAY 0.617021 (-5760 1585);
PAINT ORANGE (-5760 1585);
FORCEPROP 2 LASTPROP $XRERR UNIQUE?
J 0
(-6000 1585);
DISPLAY 0.638298 (-6000 1585);
PAINT MONO (-6000 1585);
DISPLAY INVISIBLE (-6000 1585);
WIRE 16 -1 (-5825 1975)(-5375 1975);
WIRE 16 -1 (-5825 1225)(-5825 1975);
WIRE 16 -1 (-7025 1975)(-5825 1975);
FORCEPROP 2 LAST SIG_NAME PU_BIOS_SPI_HOLD1_N
J 0
(-7010 1985);
DISPLAY 0.617021 (-7010 1985);
PAINT ORANGE (-7010 1985);
WIRE 16 -1 (-6300 1225)(-5825 1225);
WIRE 16 -1 (-5925 1925)(-5375 1925);
WIRE 16 -1 (-5925 1500)(-5925 1925);
WIRE 16 -1 (-7025 1925)(-5925 1925);
FORCEPROP 2 LAST SIG_NAME PU_BIOS_SPI_WP1_N
J 0
(-7025 1935);
DISPLAY 0.617021 (-7025 1935);
PAINT ORANGE (-7025 1935);
WIRE 16 -1 (-6325 1500)(-5925 1500);
WIRE 16 -1 (-5375 1875)(-6100 1875);
FORCEPROP 2 LAST SIG_NAME SPI_MISO_R1
J 2
(-5475 1885);
DISPLAY 0.617021 (-5475 1885);
PAINT ORANGE (-5475 1885);
FORCEPROP 2 LASTPROP $XRERR UNIQUE?
J 0
(-5715 1885);
DISPLAY 0.638298 (-5715 1885);
PAINT MONO (-5715 1885);
DISPLAY INVISIBLE (-5715 1885);
WIRE 16 -1 (-5375 1625)(-6175 1625);
WIRE 16 -1 (-6175 2225)(-6175 1625);
WIRE 16 -1 (-6175 1625)(-7025 1625);
FORCEPROP 2 LAST SIG_NAME SPI_CS0_SECONDARY_R_N
J 0
(-7025 1635);
DISPLAY 0.617021 (-7025 1635);
PAINT ORANGE (-7025 1635);
WIRE 16 -1 (-5375 1825)(-6350 1825);
FORCEPROP 2 LAST SIG_NAME SPI_SWITCH_MOSI_R1
J 0
(-5825 1835);
DISPLAY 0.617021 (-5825 1835);
PAINT ORANGE (-5825 1835);
FORCEPROP 2 LASTPROP $XRERR UNIQUE?
J 0
(-6065 1835);
DISPLAY 0.638298 (-6065 1835);
PAINT MONO (-6065 1835);
DISPLAY INVISIBLE (-6065 1835);
WIRE 16 -1 (-6450 3825)(-5450 3825);
FORCEPROP 2 LAST SIG_NAME SPI_CLK_R0
J 0
(-5885 3825);
DISPLAY 0.617021 (-5885 3825);
PAINT ORANGE (-5885 3825);
FORCEPROP 2 LASTPROP $XRERR UNIQUE?
J 0
(-6125 3825);
DISPLAY 0.638298 (-6125 3825);
PAINT MONO (-6125 3825);
DISPLAY INVISIBLE (-6125 3825);
WIRE 16 -1 (-5450 3975)(-6175 3975);
FORCEPROP 2 LAST SIG_NAME SPI_MISO_R0
J 2
(-5550 3985);
DISPLAY 0.617021 (-5550 3985);
PAINT ORANGE (-5550 3985);
FORCEPROP 2 LASTPROP $XRERR UNIQUE?
J 0
(-5790 3985);
DISPLAY 0.638298 (-5790 3985);
PAINT MONO (-5790 3985);
DISPLAY INVISIBLE (-5790 3985);
WIRE 16 -1 (-5450 3925)(-6425 3925);
FORCEPROP 2 LAST SIG_NAME SPI_SWITCH_MOSI_R0
J 0
(-5900 3935);
DISPLAY 0.617021 (-5900 3935);
PAINT ORANGE (-5900 3935);
FORCEPROP 2 LASTPROP $XRERR UNIQUE?
J 0
(-6140 3935);
DISPLAY 0.638298 (-6140 3935);
PAINT MONO (-6140 3935);
DISPLAY INVISIBLE (-6140 3935);
WIRE 16 -1 (-6425 1725)(-5375 1725);
FORCEPROP 2 LAST SIG_NAME SPI_CLK_R1
J 0
(-5810 1725);
DISPLAY 0.617021 (-5810 1725);
PAINT ORANGE (-5810 1725);
FORCEPROP 2 LASTPROP $XRERR UNIQUE?
J 0
(-6050 1725);
DISPLAY 0.638298 (-6050 1725);
PAINT MONO (-6050 1725);
DISPLAY INVISIBLE (-6050 1725);
WIRE 16 -1 (-7100 3825)(-6650 3825);
FORCEPROP 2 LAST SIG_NAME SPI_SWITCH_CLK
J 0
(-7100 3835);
DISPLAY 0.617021 (-7100 3835);
PAINT ORANGE (-7100 3835);
WIRE 16 -1 (-7100 3975)(-6375 3975);
FORCEPROP 2 LAST SIG_NAME SPI_SWITCH_MISO
J 0
(-7100 3985);
DISPLAY 0.617021 (-7100 3985);
PAINT ORANGE (-7100 3985);
WIRE 16 -1 (-7100 3925)(-6625 3925);
FORCEPROP 2 LAST SIG_NAME SPI_SWITCH_MOSI
J 0
(-7100 3935);
DISPLAY 0.617021 (-7100 3935);
PAINT ORANGE (-7100 3935);
WIRE 16 -1 (-7325 3600)(-6600 3600);
FORCEPROP 2 LAST SIG_NAME SPI_BIOS_SOCKET_IO2
J 0
(-7285 3610);
DISPLAY 0.617021 (-7285 3610);
PAINT ORANGE (-7285 3610);
WIRE 16 -1 (-7325 3325)(-6575 3325);
FORCEPROP 2 LAST SIG_NAME SPI_BIOS_SOCKET_IO3
J 0
(-7285 3335);
DISPLAY 0.617021 (-7285 3335);
PAINT ORANGE (-7285 3335);
WIRE 16 -1 (-7025 1875)(-6300 1875);
FORCEPROP 2 LAST SIG_NAME SPI_SWITCH_MISO
J 0
(-7025 1885);
DISPLAY 0.617021 (-7025 1885);
PAINT ORANGE (-7025 1885);
WIRE 16 -1 (-7025 1725)(-6625 1725);
FORCEPROP 2 LAST SIG_NAME SPI_SWITCH_CLK
J 0
(-7025 1735);
DISPLAY 0.617021 (-7025 1735);
PAINT ORANGE (-7025 1735);
WIRE 16 -1 (-7025 1825)(-6550 1825);
FORCEPROP 2 LAST SIG_NAME SPI_SWITCH_MOSI
J 0
(-7025 1835);
DISPLAY 0.617021 (-7025 1835);
PAINT ORANGE (-7025 1835);
WIRE 16 -1 (-7250 1500)(-6525 1500);
FORCEPROP 2 LAST SIG_NAME SPI_BIOS_SOCKET_IO2
J 0
(-7210 1510);
DISPLAY 0.617021 (-7210 1510);
PAINT ORANGE (-7210 1510);
WIRE 16 -1 (-7250 1225)(-6500 1225);
FORCEPROP 2 LAST SIG_NAME SPI_BIOS_SOCKET_IO3
J 0
(-7210 1235);
DISPLAY 0.617021 (-7210 1235);
PAINT ORANGE (-7210 1235);
DOT 1 (-6175 1625);
DOT 1 (-6175 2550);
DOT 1 (-6250 3725);
DOT 1 (-5925 1925);
DOT 1 (-5825 1975);
DOT 1 (-5875 2550);
DOT 1 (-5525 2550);
DOT 1 (-5900 4075);
DOT 1 (-6000 4025);
DOT 1 (-6250 4650);
DOT 1 (-5950 4650);
DOT 1 (-5600 4650);
DOT 1 (-3925 2550);
DOT 1 (-3625 2200);
DOT 1 (-1750 1650);
DOT 1 (-1750 3750);
DOT 1 (-3775 4300);
DOT 1 (-4075 4650);
FORCENOTE
ROOM=SM_MEM
(-7890 186) 0;
DISPLAY LEFT (-7890 186);
DISPLAY 0.765957 (-7890 186);
PAINT PURPLE (-7890 186);
FORCENOTE
SECONDARY FLASH - BOTTOM SIDE OF BOARD
(-5600 2675) 0;
DISPLAY LEFT (-5600 2675);
DISPLAY 1.021277 (-5600 2675);
PAINT PURPLE (-5600 2675);
FORCENOTE
PRIMARY FLASH - TOP SIDE OF BOARD
(-5500 4800) 0;
DISPLAY LEFT (-5500 4800);
DISPLAY 1.021277 (-5500 4800);
PAINT PURPLE (-5500 4800);
QUIT
